FILE_TYPE = MACRO_DRAWING;
SET COLOR_WIRE YELLOW;
SET COLOR_PROP ORANGE;
SET COLOR_DOT WHITE;
SET COLOR_ARC YELLOW;
SET COLOR_BODY GREEN;
SET COLOR_NOTE PURPLE;
SET PROP_DISPLAY VALUE;
SET PAGE_NUMBER P252;
FORCEADD UNIVERSAL_GND..1
(-5900 2100);
FORCEPROP 3 LASTPIN (-5900 2150) SIG_NAME GND\g
J 0
(-5890 2160);
DISPLAY 0.659574 (-5890 2160);
PAINT MONO (-5890 2160);
DISPLAY INVISIBLE (-5890 2160);
FORCEPROP 2 LAST ROOM IO_SLOT
J 1
(-6125 2175);
DISPLAY 0.744681 (-6125 2175);
FORCEPROP 2 LAST CDS_LIB pure_quanta_power
J 0
(-5900 2100);
PAINT MONO (-5900 2100);
DISPLAY INVISIBLE (-5900 2100);
FORCEPROP 1 LAST HDL_POWER GND
J 1
(-5875 2025);
DISPLAY 0.872340 (-5875 2025);
PAINT GREEN (-5875 2025);
DISPLAY INVISIBLE (-5875 2025);
FORCEPROP 1 LAST PATH I1
J 0
(-5825 2100);
DISPLAY 0.872340 (-5825 2100);
PAINT AQUA (-5825 2100);
DISPLAY INVISIBLE (-5825 2100);
FORCEADD Q_RES..2
(-5350 2975);
FORCEPROP 1 LAST LOCATION R320
J 0
(-5305 3100);
DISPLAY 0.978723 (-5305 3100);
FORCEPROP 2 LAST $SEC 1
J 0
(-5300 3200);
DISPLAY 0.680851 (-5300 3200);
PAINT MONO (-5300 3200);
DISPLAY INVISIBLE (-5300 3200);
FORCEPROP 2 LAST CDS_SEC 1
J 0
(-5300 3200);
DISPLAY 1.021277 (-5300 3200);
DISPLAY INVISIBLE (-5300 3200);
FORCEPROP 1 LASTPIN (-5350 3075) $PN 1
J 0
(-5345 3037);
DISPLAY 0.787234 (-5345 3037);
FORCEPROP 1 LASTPIN (-5350 2875) $PN 2
J 0
(-5345 2885);
DISPLAY 0.787234 (-5345 2885);
FORCEPROP 1 LAST VALUE 10K
J 0
(-5305 3050);
DISPLAY 0.638298 (-5305 3050);
FORCEPROP 1 LAST TOLERANCE 1%
J 0
(-5305 3000);
DISPLAY 0.638298 (-5305 3000);
FORCEPROP 1 LAST PACK_TYPE 0402LF
J 0
(-5310 2800);
DISPLAY 0.638298 (-5310 2800);
FORCEPROP 1 LAST WATTAGE 1/16W
J 0
(-5310 2950);
DISPLAY 0.638298 (-5310 2950);
FORCEPROP 1 LAST MATERIAL EMPTY
J 0
(-5310 2900);
DISPLAY 0.638298 (-5310 2900);
PAINT RED (-5310 2900);
FORCEPROP 2 LAST CDS_LIB pure_quanta
J 0
(-5350 2975);
PAINT MONO (-5350 2975);
DISPLAY INVISIBLE (-5350 2975);
FORCEPROP 1 LAST PATH I10
J 0
(-5300 3150);
DISPLAY 0.978723 (-5300 3150);
PAINT WHITE (-5300 3150);
DISPLAY INVISIBLE (-5300 3150);
FORCEPROP 1 LAST PART_NUMBER CS31002FB08
J 0
(-5310 2850);
DISPLAY 0.510638 (-5310 2850);
DISPLAY INVISIBLE (-5310 2850);
FORCEADD OFFPAGE..2
(-4225 2700);
FORCEPROP 2 LAST $XR0 251 
J 0
(-4036 2700);
DISPLAY 0.638298 (-4036 2700);
PAINT MONO (-4036 2700);
FORCEPROP 2 LAST CDS_LIB standard
J 0
(-4225 2700);
PAINT MONO (-4225 2700);
DISPLAY INVISIBLE (-4225 2700);
FORCEPROP 1 LAST OFFPAGE TRUE
J 0
(-3900 2575);
DISPLAY 0.872340 (-3900 2575);
DISPLAY INVISIBLE (-3900 2575);
FORCEPROP 1 LAST COMMENT_BODY TRUE
J 0
(-4270 2605);
DISPLAY 0.872340 (-4270 2605);
PAINT GREEN (-4270 2605);
DISPLAY INVISIBLE (-4270 2605);
FORCEPROP 2 LAST PATH I11
J 0
(-4025 2750);
DISPLAY 0.680851 (-4025 2750);
DISPLAY INVISIBLE (-4025 2750);
FORCEADD OFFPAGE..2
(-4225 2625);
FORCEPROP 2 LAST $XR0 251 
J 0
(-4036 2625);
DISPLAY 0.638298 (-4036 2625);
PAINT MONO (-4036 2625);
FORCEPROP 2 LAST CDS_LIB standard
J 0
(-4225 2625);
PAINT MONO (-4225 2625);
DISPLAY INVISIBLE (-4225 2625);
FORCEPROP 1 LAST OFFPAGE TRUE
J 0
(-3900 2500);
DISPLAY 0.872340 (-3900 2500);
DISPLAY INVISIBLE (-3900 2500);
FORCEPROP 1 LAST COMMENT_BODY TRUE
J 0
(-4270 2530);
DISPLAY 0.872340 (-4270 2530);
PAINT GREEN (-4270 2530);
DISPLAY INVISIBLE (-4270 2530);
FORCEPROP 2 LAST PATH I12
J 0
(-4025 2675);
DISPLAY 0.680851 (-4025 2675);
DISPLAY INVISIBLE (-4025 2675);
FORCEADD OFFPAGE..2
(-4225 2550);
FORCEPROP 2 LAST $XR0 251 
J 0
(-4036 2550);
DISPLAY 0.638298 (-4036 2550);
PAINT MONO (-4036 2550);
FORCEPROP 2 LAST CDS_LIB standard
J 0
(-4225 2550);
PAINT MONO (-4225 2550);
DISPLAY INVISIBLE (-4225 2550);
FORCEPROP 1 LAST OFFPAGE TRUE
J 0
(-3900 2425);
DISPLAY 0.872340 (-3900 2425);
DISPLAY INVISIBLE (-3900 2425);
FORCEPROP 1 LAST COMMENT_BODY TRUE
J 0
(-4270 2455);
DISPLAY 0.872340 (-4270 2455);
PAINT GREEN (-4270 2455);
DISPLAY INVISIBLE (-4270 2455);
FORCEPROP 2 LAST PATH I13
J 0
(-4025 2600);
DISPLAY 0.680851 (-4025 2600);
DISPLAY INVISIBLE (-4025 2600);
FORCEADD OFFPAGE..1
(-7125 4675);
FORCEPROP 2 LAST $XR5 253 
J 0
(-7976 4675);
DISPLAY 0.638298 (-7976 4675);
PAINT MONO (-7976 4675);
FORCEPROP 2 LAST $XR4 246 
J 0
(-7856 4675);
DISPLAY 0.638298 (-7856 4675);
PAINT MONO (-7856 4675);
FORCEPROP 2 LAST $XR3 241 
J 0
(-7736 4675);
DISPLAY 0.638298 (-7736 4675);
PAINT MONO (-7736 4675);
FORCEPROP 2 LAST $XR2 139 
J 0
(-7616 4675);
DISPLAY 0.638298 (-7616 4675);
PAINT MONO (-7616 4675);
FORCEPROP 2 LAST $XR1 132 
J 0
(-7496 4675);
DISPLAY 0.638298 (-7496 4675);
PAINT MONO (-7496 4675);
FORCEPROP 2 LAST $XR0 80 
J 0
(-7376 4675);
DISPLAY 0.638298 (-7376 4675);
PAINT MONO (-7376 4675);
FORCEPROP 2 LAST CDS_LIB standard
J 0
(-7125 4675);
DISPLAY INVISIBLE (-7125 4675);
FORCEPROP 1 LAST OFFPAGE TRUE
J 0
(-6800 4550);
DISPLAY 0.872340 (-6800 4550);
DISPLAY INVISIBLE (-6800 4550);
FORCEPROP 1 LAST COMMENT_BODY TRUE
J 0
(-7000 4575);
DISPLAY 0.872340 (-7000 4575);
PAINT GREEN (-7000 4575);
DISPLAY INVISIBLE (-7000 4575);
FORCEPROP 2 LAST PATH I14
J 0
(-7375 4725);
DISPLAY 0.680851 (-7375 4725);
DISPLAY INVISIBLE (-7375 4725);
FORCEADD OFFPAGE..3
R 2
(-6600 4425);
FORCEPROP 2 LAST $XR1 246 
J 0
(-7030 4425);
DISPLAY 0.638298 (-7030 4425);
PAINT MONO (-7030 4425);
FORCEPROP 2 LAST $XR0 251 
J 0
(-6910 4425);
DISPLAY 0.638298 (-6910 4425);
PAINT MONO (-6910 4425);
FORCEPROP 2 LAST CDS_LIB standard
J 2
(-6600 4425);
DISPLAY INVISIBLE (-6600 4425);
FORCEPROP 1 LAST OFFPAGE TRUE
J 2
(-6925 4300);
DISPLAY 0.872340 (-6925 4300);
DISPLAY INVISIBLE (-6925 4300);
FORCEPROP 1 LAST COMMENT_BODY TRUE
J 2
(-6550 4325);
DISPLAY 0.872340 (-6550 4325);
PAINT GREEN (-6550 4325);
DISPLAY INVISIBLE (-6550 4325);
FORCEPROP 2 LAST PATH I15
J 0
(-6875 4475);
DISPLAY 0.680851 (-6875 4475);
DISPLAY INVISIBLE (-6875 4475);
FORCEADD OFFPAGE..3
R 2
(-6600 4325);
FORCEPROP 2 LAST $XR1 148 
J 0
(-7030 4325);
DISPLAY 0.638298 (-7030 4325);
PAINT MONO (-7030 4325);
FORCEPROP 2 LAST $XR0 251 
J 0
(-6910 4325);
DISPLAY 0.638298 (-6910 4325);
PAINT MONO (-6910 4325);
FORCEPROP 2 LAST CDS_LIB standard
J 2
(-6600 4325);
DISPLAY INVISIBLE (-6600 4325);
FORCEPROP 1 LAST OFFPAGE TRUE
J 2
(-6925 4200);
DISPLAY 0.872340 (-6925 4200);
DISPLAY INVISIBLE (-6925 4200);
FORCEPROP 1 LAST COMMENT_BODY TRUE
J 2
(-6550 4225);
DISPLAY 0.872340 (-6550 4225);
PAINT GREEN (-6550 4225);
DISPLAY INVISIBLE (-6550 4225);
FORCEPROP 2 LAST PATH I16
J 0
(-6875 4375);
DISPLAY 0.680851 (-6875 4375);
DISPLAY INVISIBLE (-6875 4375);
FORCEADD OFFPAGE..3
R 2
(-6600 4225);
FORCEPROP 2 LAST $XR1 148 
J 0
(-7030 4225);
DISPLAY 0.638298 (-7030 4225);
PAINT MONO (-7030 4225);
FORCEPROP 2 LAST $XR0 251 
J 0
(-6910 4225);
DISPLAY 0.638298 (-6910 4225);
PAINT MONO (-6910 4225);
FORCEPROP 2 LAST CDS_LIB standard
J 2
(-6600 4225);
DISPLAY INVISIBLE (-6600 4225);
FORCEPROP 1 LAST OFFPAGE TRUE
J 2
(-6925 4100);
DISPLAY 0.872340 (-6925 4100);
DISPLAY INVISIBLE (-6925 4100);
FORCEPROP 1 LAST COMMENT_BODY TRUE
J 2
(-6550 4125);
DISPLAY 0.872340 (-6550 4125);
PAINT GREEN (-6550 4125);
DISPLAY INVISIBLE (-6550 4125);
FORCEPROP 2 LAST PATH I17
J 0
(-6875 4275);
DISPLAY 0.680851 (-6875 4275);
DISPLAY INVISIBLE (-6875 4275);
FORCEADD OFFPAGE..5
(-6600 4275);
FORCEPROP 2 LAST $XR1 251 
J 0
(-7005 4275);
DISPLAY 0.638298 (-7005 4275);
PAINT MONO (-7005 4275);
FORCEPROP 2 LAST $XR0 148 
J 0
(-6885 4275);
DISPLAY 0.638298 (-6885 4275);
PAINT MONO (-6885 4275);
FORCEPROP 2 LAST CDS_LIB standard
J 2
(-6600 4275);
DISPLAY INVISIBLE (-6600 4275);
FORCEPROP 1 LAST OFFPAGE TRUE
J 0
(-6275 4150);
DISPLAY 0.872340 (-6275 4150);
DISPLAY INVISIBLE (-6275 4150);
FORCEPROP 1 LAST COMMENT_BODY TRUE
J 0
(-6500 4200);
DISPLAY 0.872340 (-6500 4200);
PAINT GREEN (-6500 4200);
DISPLAY INVISIBLE (-6500 4200);
FORCEPROP 2 LAST PATH I18
J 0
(-6875 4325);
DISPLAY 0.680851 (-6875 4325);
DISPLAY INVISIBLE (-6875 4325);
FORCEADD OFFPAGE..5
(-6600 4375);
FORCEPROP 2 LAST $XR1 251 
J 0
(-7005 4375);
DISPLAY 0.638298 (-7005 4375);
PAINT MONO (-7005 4375);
FORCEPROP 2 LAST $XR0 148 
J 0
(-6885 4375);
DISPLAY 0.638298 (-6885 4375);
PAINT MONO (-6885 4375);
FORCEPROP 2 LAST CDS_LIB standard
J 2
(-6600 4375);
DISPLAY INVISIBLE (-6600 4375);
FORCEPROP 1 LAST OFFPAGE TRUE
J 0
(-6275 4250);
DISPLAY 0.872340 (-6275 4250);
DISPLAY INVISIBLE (-6275 4250);
FORCEPROP 1 LAST COMMENT_BODY TRUE
J 0
(-6500 4300);
DISPLAY 0.872340 (-6500 4300);
PAINT GREEN (-6500 4300);
DISPLAY INVISIBLE (-6500 4300);
FORCEPROP 2 LAST PATH I19
J 0
(-6875 4425);
DISPLAY 0.680851 (-6875 4425);
DISPLAY INVISIBLE (-6875 4425);
FORCEADD Q_RES..2
(-5900 2325);
FORCEPROP 1 LAST LOCATION R317
J 0
(-5855 2450);
DISPLAY 0.978723 (-5855 2450);
FORCEPROP 2 LAST $SEC 1
J 0
(-5850 2550);
DISPLAY 0.680851 (-5850 2550);
PAINT MONO (-5850 2550);
DISPLAY INVISIBLE (-5850 2550);
FORCEPROP 2 LAST CDS_SEC 1
J 0
(-5850 2550);
DISPLAY 1.021277 (-5850 2550);
DISPLAY INVISIBLE (-5850 2550);
FORCEPROP 1 LASTPIN (-5900 2425) $PN 1
J 0
(-5895 2387);
DISPLAY 0.787234 (-5895 2387);
FORCEPROP 1 LASTPIN (-5900 2225) $PN 2
J 0
(-5895 2235);
DISPLAY 0.787234 (-5895 2235);
FORCEPROP 1 LAST TOLERANCE 1%
J 0
(-5855 2350);
DISPLAY 0.638298 (-5855 2350);
FORCEPROP 1 LAST WATTAGE 1/16W
J 0
(-5860 2300);
DISPLAY 0.638298 (-5860 2300);
FORCEPROP 1 LAST MATERIAL CHIP
J 0
(-5860 2250);
DISPLAY 0.638298 (-5860 2250);
FORCEPROP 1 LAST PACK_TYPE 0402LF
J 0
(-5860 2200);
DISPLAY 0.638298 (-5860 2200);
FORCEPROP 1 LAST VALUE 1K
J 0
(-5855 2400);
DISPLAY 0.638298 (-5855 2400);
FORCEPROP 2 LAST CDS_LIB pure_quanta
J 0
(-5900 2325);
PAINT MONO (-5900 2325);
DISPLAY INVISIBLE (-5900 2325);
FORCEPROP 1 LAST PATH I2
J 0
(-5850 2500);
DISPLAY 0.978723 (-5850 2500);
PAINT WHITE (-5850 2500);
DISPLAY INVISIBLE (-5850 2500);
FORCEPROP 1 LAST PART_NUMBER CS21002FB06
J 0
(-5860 2200);
DISPLAY 0.510638 (-5860 2200);
DISPLAY INVISIBLE (-5860 2200);
FORCEADD OFFPAGE..5
(-6600 4475);
FORCEPROP 2 LAST $XR1 246 
J 0
(-7005 4475);
DISPLAY 0.638298 (-7005 4475);
PAINT MONO (-7005 4475);
FORCEPROP 2 LAST $XR0 251 
J 0
(-6885 4475);
DISPLAY 0.638298 (-6885 4475);
PAINT MONO (-6885 4475);
FORCEPROP 2 LAST CDS_LIB standard
J 2
(-6600 4475);
DISPLAY INVISIBLE (-6600 4475);
FORCEPROP 1 LAST OFFPAGE TRUE
J 0
(-6275 4350);
DISPLAY 0.872340 (-6275 4350);
DISPLAY INVISIBLE (-6275 4350);
FORCEPROP 1 LAST COMMENT_BODY TRUE
J 0
(-6500 4400);
DISPLAY 0.872340 (-6500 4400);
PAINT GREEN (-6500 4400);
DISPLAY INVISIBLE (-6500 4400);
FORCEPROP 2 LAST PATH I20
J 0
(-6850 4525);
DISPLAY 0.680851 (-6850 4525);
DISPLAY INVISIBLE (-6850 4525);
FORCEADD Q_RES..2
R 2
(-6600 5025);
FORCEPROP 1 LAST LOCATION R1822
J 2
(-6645 5150);
DISPLAY 0.978723 (-6645 5150);
FORCEPROP 2 LAST $SEC 1
J 0
(-6650 5250);
DISPLAY 0.680851 (-6650 5250);
PAINT MONO (-6650 5250);
DISPLAY INVISIBLE (-6650 5250);
FORCEPROP 2 LAST CDS_SEC 1
J 0
(-6650 5250);
DISPLAY 1.021277 (-6650 5250);
DISPLAY INVISIBLE (-6650 5250);
FORCEPROP 1 LASTPIN (-6600 5125) $PN 1
J 2
(-6605 5087);
DISPLAY 0.787234 (-6605 5087);
FORCEPROP 1 LASTPIN (-6600 4925) $PN 2
J 2
(-6605 4935);
DISPLAY 0.787234 (-6605 4935);
FORCEPROP 1 LAST PACK_TYPE 0402LF
J 2
(-6640 4900);
DISPLAY 0.638298 (-6640 4900);
FORCEPROP 1 LAST MATERIAL CHIP
J 2
(-6640 4950);
DISPLAY 0.638298 (-6640 4950);
FORCEPROP 1 LAST WATTAGE 1/16W
J 2
(-6640 5000);
DISPLAY 0.638298 (-6640 5000);
FORCEPROP 1 LAST TOLERANCE 1%
J 2
(-6645 5050);
DISPLAY 0.638298 (-6645 5050);
FORCEPROP 1 LAST VALUE 10K
J 2
(-6645 5100);
DISPLAY 0.638298 (-6645 5100);
FORCEPROP 2 LAST CDS_LIB pure_quanta
J 2
(-6600 5025);
PAINT MONO (-6600 5025);
DISPLAY INVISIBLE (-6600 5025);
FORCEPROP 1 LAST PATH I21
J 2
(-6650 5200);
DISPLAY 0.978723 (-6650 5200);
PAINT WHITE (-6650 5200);
DISPLAY INVISIBLE (-6650 5200);
FORCEPROP 1 LAST PART_NUMBER CS31002FB08
J 2
(-6640 4850);
DISPLAY 0.638298 (-6640 4850);
DISPLAY INVISIBLE (-6640 4850);
FORCEADD UNIVERSAL_POWER..1
(-6600 5300);
FORCEPROP 3 LASTPIN (-6600 5250) SIG_NAME P3V3_AUX\g
J 0
(-6590 5260);
DISPLAY 0.659574 (-6590 5260);
PAINT MONO (-6590 5260);
DISPLAY INVISIBLE (-6590 5260);
FORCEPROP 1 LAST HDL_POWER P3V3_AUX
J 1
(-6600 5350);
DISPLAY 0.872340 (-6600 5350);
PAINT GREEN (-6600 5350);
FORCEPROP 2 LAST CDS_LIB pure_quanta_power
J 0
(-6600 5300);
DISPLAY INVISIBLE (-6600 5300);
FORCEPROP 1 LAST PATH I22
J 0
(-6550 5325);
DISPLAY 0.872340 (-6550 5325);
PAINT AQUA (-6550 5325);
DISPLAY INVISIBLE (-6550 5325);
FORCEADD Q_RES..1
R 2
(-5400 4225);
FORCEPROP 1 LAST LOCATION R3526
J 2
(-5175 4225);
DISPLAY 0.510638 (-5175 4225);
FORCEPROP 0 LAST $SEC 1
J 2
(-5175 4275);
DISPLAY INVISIBLE (-5175 4275);
FORCEPROP 0 LAST CDS_SEC 1
J 2
(-5175 4275);
DISPLAY INVISIBLE (-5175 4275);
FORCEPROP 1 LASTPIN (-5300 4225) $PN 1
J 2
(-5312 4237);
DISPLAY 0.787234 (-5312 4237);
PAINT MONO (-5312 4237);
DISPLAY INVISIBLE (-5312 4237);
FORCEPROP 1 LASTPIN (-5500 4225) $PN 2
J 2
(-5462 4237);
DISPLAY 0.787234 (-5462 4237);
PAINT MONO (-5462 4237);
DISPLAY INVISIBLE (-5462 4237);
FORCEPROP 1 LAST TOLERANCE 5%
J 2
(-5575 4225);
DISPLAY 0.510638 (-5575 4225);
FORCEPROP 1 LAST VALUE 0
J 0
(-5550 4225);
DISPLAY 0.510638 (-5550 4225);
FORCEPROP 1 LAST MATERIAL CHIP
J 2
(-5650 4225);
DISPLAY 0.510638 (-5650 4225);
FORCEPROP 1 LAST PACK_TYPE 0402LF
J 2
(-5650 4225);
DISPLAY 0.510638 (-5650 4225);
DISPLAY INVISIBLE (-5650 4225);
FORCEPROP 1 LAST WATTAGE 1/16W
J 0
(-5500 4150);
DISPLAY 0.319149 (-5500 4150);
DISPLAY INVISIBLE (-5500 4150);
FORCEPROP 2 LAST CDS_LIB pure_quanta
J 2
(-5400 4225);
DISPLAY INVISIBLE (-5400 4225);
FORCEPROP 1 LAST PATH I23
J 2
(-5350 4375);
DISPLAY 0.978723 (-5350 4375);
PAINT WHITE (-5350 4375);
DISPLAY INVISIBLE (-5350 4375);
FORCEPROP 1 LAST PART_NUMBER CS00002JB13
J 2
(-5325 4175);
DISPLAY 0.319149 (-5325 4175);
DISPLAY INVISIBLE (-5325 4175);
FORCEADD Q_RES..1
R 2
(-5400 4275);
FORCEPROP 1 LAST LOCATION R3527
J 2
(-5175 4275);
DISPLAY 0.510638 (-5175 4275);
FORCEPROP 0 LAST $SEC 1
J 2
(-5175 4325);
DISPLAY INVISIBLE (-5175 4325);
FORCEPROP 0 LAST CDS_SEC 1
J 2
(-5175 4325);
DISPLAY INVISIBLE (-5175 4325);
FORCEPROP 1 LASTPIN (-5300 4275) $PN 1
J 2
(-5312 4287);
DISPLAY 0.787234 (-5312 4287);
PAINT MONO (-5312 4287);
DISPLAY INVISIBLE (-5312 4287);
FORCEPROP 1 LASTPIN (-5500 4275) $PN 2
J 2
(-5462 4287);
DISPLAY 0.787234 (-5462 4287);
PAINT MONO (-5462 4287);
DISPLAY INVISIBLE (-5462 4287);
FORCEPROP 1 LAST TOLERANCE 5%
J 2
(-5575 4275);
DISPLAY 0.510638 (-5575 4275);
FORCEPROP 1 LAST VALUE 0
J 0
(-5550 4275);
DISPLAY 0.510638 (-5550 4275);
FORCEPROP 1 LAST MATERIAL CHIP
J 2
(-5650 4275);
DISPLAY 0.510638 (-5650 4275);
FORCEPROP 2 LAST CDS_LIB pure_quanta
J 2
(-5400 4275);
DISPLAY INVISIBLE (-5400 4275);
FORCEPROP 1 LAST PACK_TYPE 0402LF
J 2
(-5300 4175);
DISPLAY 0.510638 (-5300 4175);
DISPLAY INVISIBLE (-5300 4175);
FORCEPROP 1 LAST WATTAGE 1/16W
J 0
(-5575 4175);
DISPLAY 0.510638 (-5575 4175);
DISPLAY INVISIBLE (-5575 4175);
FORCEPROP 1 LAST PATH I24
J 2
(-5350 4425);
DISPLAY 0.978723 (-5350 4425);
PAINT WHITE (-5350 4425);
DISPLAY INVISIBLE (-5350 4425);
FORCEPROP 1 LAST PART_NUMBER CS00002JB13
J 2
(-5300 4225);
DISPLAY 0.510638 (-5300 4225);
DISPLAY INVISIBLE (-5300 4225);
FORCEADD Q_RES..1
R 2
(-5400 4325);
FORCEPROP 1 LAST LOCATION R2967
J 2
(-5175 4325);
DISPLAY 0.510638 (-5175 4325);
FORCEPROP 0 LAST $SEC 1
J 2
(-5175 4375);
DISPLAY INVISIBLE (-5175 4375);
FORCEPROP 0 LAST CDS_SEC 1
J 2
(-5175 4375);
DISPLAY INVISIBLE (-5175 4375);
FORCEPROP 1 LASTPIN (-5300 4325) $PN 1
J 2
(-5312 4337);
DISPLAY 0.787234 (-5312 4337);
PAINT MONO (-5312 4337);
DISPLAY INVISIBLE (-5312 4337);
FORCEPROP 1 LASTPIN (-5500 4325) $PN 2
J 2
(-5462 4337);
DISPLAY 0.787234 (-5462 4337);
PAINT MONO (-5462 4337);
DISPLAY INVISIBLE (-5462 4337);
FORCEPROP 1 LAST VALUE 0
J 0
(-5550 4325);
DISPLAY 0.510638 (-5550 4325);
FORCEPROP 1 LAST TOLERANCE 5%
J 2
(-5575 4325);
DISPLAY 0.510638 (-5575 4325);
FORCEPROP 1 LAST MATERIAL CHIP
J 2
(-5650 4325);
DISPLAY 0.510638 (-5650 4325);
FORCEPROP 1 LAST PACK_TYPE 0402LF
J 2
(-5650 4325);
DISPLAY 0.510638 (-5650 4325);
DISPLAY INVISIBLE (-5650 4325);
FORCEPROP 1 LAST WATTAGE 1/16W
J 0
(-5500 4250);
DISPLAY 0.319149 (-5500 4250);
DISPLAY INVISIBLE (-5500 4250);
FORCEPROP 2 LAST CDS_LIB pure_quanta
J 2
(-5400 4325);
DISPLAY INVISIBLE (-5400 4325);
FORCEPROP 1 LAST PATH I25
J 2
(-5350 4475);
DISPLAY 0.978723 (-5350 4475);
PAINT WHITE (-5350 4475);
DISPLAY INVISIBLE (-5350 4475);
FORCEPROP 1 LAST PART_NUMBER CS00002JB13
J 2
(-5325 4275);
DISPLAY 0.319149 (-5325 4275);
DISPLAY INVISIBLE (-5325 4275);
FORCEADD Q_RES..1
R 2
(-5400 4375);
FORCEPROP 1 LAST LOCATION R2968
J 2
(-5175 4375);
DISPLAY 0.510638 (-5175 4375);
FORCEPROP 0 LAST $SEC 1
J 2
(-5175 4425);
DISPLAY INVISIBLE (-5175 4425);
FORCEPROP 0 LAST CDS_SEC 1
J 2
(-5175 4425);
DISPLAY INVISIBLE (-5175 4425);
FORCEPROP 1 LASTPIN (-5300 4375) $PN 1
J 2
(-5312 4387);
DISPLAY 0.787234 (-5312 4387);
PAINT MONO (-5312 4387);
DISPLAY INVISIBLE (-5312 4387);
FORCEPROP 1 LASTPIN (-5500 4375) $PN 2
J 2
(-5462 4387);
DISPLAY 0.787234 (-5462 4387);
PAINT MONO (-5462 4387);
DISPLAY INVISIBLE (-5462 4387);
FORCEPROP 1 LAST TOLERANCE 5%
J 2
(-5575 4375);
DISPLAY 0.510638 (-5575 4375);
FORCEPROP 1 LAST VALUE 0
J 0
(-5550 4375);
DISPLAY 0.510638 (-5550 4375);
FORCEPROP 1 LAST MATERIAL CHIP
J 2
(-5650 4375);
DISPLAY 0.510638 (-5650 4375);
FORCEPROP 1 LAST WATTAGE 1/16W
J 0
(-5575 4275);
DISPLAY 0.510638 (-5575 4275);
DISPLAY INVISIBLE (-5575 4275);
FORCEPROP 1 LAST PACK_TYPE 0402LF
J 2
(-5300 4275);
DISPLAY 0.510638 (-5300 4275);
DISPLAY INVISIBLE (-5300 4275);
FORCEPROP 2 LAST CDS_LIB pure_quanta
J 2
(-5400 4375);
DISPLAY INVISIBLE (-5400 4375);
FORCEPROP 1 LAST PATH I26
J 2
(-5350 4525);
DISPLAY 0.978723 (-5350 4525);
PAINT WHITE (-5350 4525);
DISPLAY INVISIBLE (-5350 4525);
FORCEPROP 1 LAST PART_NUMBER CS00002JB13
J 2
(-5300 4325);
DISPLAY 0.510638 (-5300 4325);
DISPLAY INVISIBLE (-5300 4325);
FORCEADD Q_RES..1
R 2
(-5400 4425);
FORCEPROP 1 LAST LOCATION R3393
J 2
(-5175 4425);
DISPLAY 0.510638 (-5175 4425);
FORCEPROP 0 LAST SEC 1
J 2
(-5175 4475);
DISPLAY INVISIBLE (-5175 4475);
FORCEPROP 1 LASTPIN (-5300 4425) $PN 1
J 2
(-5312 4437);
DISPLAY 0.787234 (-5312 4437);
PAINT MONO (-5312 4437);
FORCEPROP 1 LASTPIN (-5500 4425) $PN 2
J 2
(-5462 4437);
DISPLAY 0.787234 (-5462 4437);
PAINT MONO (-5462 4437);
FORCEPROP 1 LAST TOLERANCE 5%
J 2
(-5575 4425);
DISPLAY 0.510638 (-5575 4425);
FORCEPROP 1 LAST VALUE 0
J 0
(-5550 4425);
DISPLAY 0.510638 (-5550 4425);
FORCEPROP 1 LAST MATERIAL CHIP
J 2
(-5650 4425);
DISPLAY 0.510638 (-5650 4425);
FORCEPROP 2 LAST CDS_LIB pure_quanta
J 2
(-5400 4425);
DISPLAY INVISIBLE (-5400 4425);
FORCEPROP 2 LAST SEC_TYPE 0402LF
J 2
(-5350 4625);
DISPLAY 1.021277 (-5350 4625);
DISPLAY INVISIBLE (-5350 4625);
FORCEPROP 1 LAST WATTAGE 1/16W
J 0
(-5500 4350);
DISPLAY 0.319149 (-5500 4350);
DISPLAY INVISIBLE (-5500 4350);
FORCEPROP 1 LAST PACK_TYPE 0402LF
J 2
(-5650 4425);
DISPLAY 0.510638 (-5650 4425);
DISPLAY INVISIBLE (-5650 4425);
FORCEPROP 1 LAST PATH I27
J 2
(-5350 4575);
DISPLAY 0.978723 (-5350 4575);
PAINT WHITE (-5350 4575);
DISPLAY INVISIBLE (-5350 4575);
FORCEPROP 1 LAST PART_NUMBER CS00002JB13
J 2
(-5325 4375);
DISPLAY 0.319149 (-5325 4375);
DISPLAY INVISIBLE (-5325 4375);
FORCEADD Q_RES..1
(-5500 4675);
FORCEPROP 1 LAST LOCATION R2268
J 0
(-5725 4675);
DISPLAY 0.638298 (-5725 4675);
FORCEPROP 0 LAST $SEC 1
J 0
(-5725 4725);
DISPLAY 0.680851 (-5725 4725);
PAINT MONO (-5725 4725);
DISPLAY INVISIBLE (-5725 4725);
FORCEPROP 0 LAST CDS_SEC 1
J 0
(-5725 4725);
DISPLAY 1.021277 (-5725 4725);
DISPLAY INVISIBLE (-5725 4725);
FORCEPROP 1 LASTPIN (-5600 4675) $PN 1
J 0
(-5588 4687);
DISPLAY 0.787234 (-5588 4687);
PAINT MONO (-5588 4687);
FORCEPROP 1 LASTPIN (-5400 4675) $PN 2
J 0
(-5438 4687);
DISPLAY 0.787234 (-5438 4687);
PAINT MONO (-5438 4687);
FORCEPROP 1 LAST TOLERANCE 5%
J 0
(-5325 4675);
DISPLAY 0.510638 (-5325 4675);
FORCEPROP 1 LAST VALUE 0
J 2
(-5350 4675);
DISPLAY 0.510638 (-5350 4675);
FORCEPROP 1 LAST MATERIAL CHIP
J 0
(-5250 4675);
DISPLAY 0.510638 (-5250 4675);
FORCEPROP 1 LAST PACK_TYPE 0402LF
J 0
(-5250 4675);
DISPLAY 0.510638 (-5250 4675);
DISPLAY INVISIBLE (-5250 4675);
FORCEPROP 1 LAST WATTAGE 1/16W
J 2
(-5400 4600);
DISPLAY 0.319149 (-5400 4600);
DISPLAY INVISIBLE (-5400 4600);
FORCEPROP 2 LAST CDS_LIB pure_quanta
J 0
(-5500 4675);
DISPLAY INVISIBLE (-5500 4675);
FORCEPROP 1 LAST PATH I28
J 0
(-5550 4825);
DISPLAY 0.978723 (-5550 4825);
PAINT WHITE (-5550 4825);
DISPLAY INVISIBLE (-5550 4825);
FORCEPROP 1 LAST PART_NUMBER CS00002JB13
J 0
(-5575 4625);
DISPLAY 0.319149 (-5575 4625);
DISPLAY INVISIBLE (-5575 4625);
FORCEADD Q_RES..1
R 2
(-5400 4475);
FORCEPROP 1 LAST LOCATION R3394
J 2
(-5175 4475);
DISPLAY 0.510638 (-5175 4475);
FORCEPROP 0 LAST $SEC 1
J 2
(-5175 4525);
DISPLAY INVISIBLE (-5175 4525);
FORCEPROP 0 LAST CDS_SEC 1
J 2
(-5175 4525);
DISPLAY INVISIBLE (-5175 4525);
FORCEPROP 1 LASTPIN (-5300 4475) $PN 1
J 2
(-5312 4487);
DISPLAY 0.787234 (-5312 4487);
PAINT MONO (-5312 4487);
DISPLAY INVISIBLE (-5312 4487);
FORCEPROP 1 LASTPIN (-5500 4475) $PN 2
J 2
(-5462 4487);
DISPLAY 0.787234 (-5462 4487);
PAINT MONO (-5462 4487);
DISPLAY INVISIBLE (-5462 4487);
FORCEPROP 1 LAST TOLERANCE 5%
J 2
(-5575 4475);
DISPLAY 0.510638 (-5575 4475);
FORCEPROP 1 LAST VALUE 0
J 0
(-5550 4475);
DISPLAY 0.510638 (-5550 4475);
FORCEPROP 1 LAST MATERIAL CHIP
J 2
(-5650 4475);
DISPLAY 0.510638 (-5650 4475);
FORCEPROP 2 LAST CDS_LIB pure_quanta
J 2
(-5400 4475);
DISPLAY INVISIBLE (-5400 4475);
FORCEPROP 1 LAST WATTAGE 1/16W
J 0
(-5500 4625);
DISPLAY 0.319149 (-5500 4625);
DISPLAY INVISIBLE (-5500 4625);
FORCEPROP 1 LAST PACK_TYPE 0402LF
J 2
(-5650 4475);
DISPLAY 0.510638 (-5650 4475);
DISPLAY INVISIBLE (-5650 4475);
FORCEPROP 1 LAST PATH I29
J 2
(-5350 4625);
DISPLAY 0.978723 (-5350 4625);
PAINT WHITE (-5350 4625);
DISPLAY INVISIBLE (-5350 4625);
FORCEPROP 1 LAST PART_NUMBER CS00002JB13
J 2
(-5325 4600);
DISPLAY 0.319149 (-5325 4600);
DISPLAY INVISIBLE (-5325 4600);
FORCEADD UNIVERSAL_GND..1
(-5625 2100);
FORCEPROP 3 LASTPIN (-5625 2150) SIG_NAME GND\g
J 0
(-5615 2160);
DISPLAY 0.659574 (-5615 2160);
PAINT MONO (-5615 2160);
DISPLAY INVISIBLE (-5615 2160);
FORCEPROP 2 LAST ROOM IO_SLOT
J 1
(-5850 2175);
DISPLAY 0.744681 (-5850 2175);
FORCEPROP 2 LAST CDS_LIB pure_quanta_power
J 0
(-5625 2100);
PAINT MONO (-5625 2100);
DISPLAY INVISIBLE (-5625 2100);
FORCEPROP 1 LAST HDL_POWER GND
J 1
(-5600 2025);
DISPLAY 0.872340 (-5600 2025);
PAINT GREEN (-5600 2025);
DISPLAY INVISIBLE (-5600 2025);
FORCEPROP 1 LAST PATH I3
J 0
(-5550 2100);
DISPLAY 0.872340 (-5550 2100);
PAINT AQUA (-5550 2100);
DISPLAY INVISIBLE (-5550 2100);
FORCEADD OFFPAGE..1
(-5000 4875);
FORCEPROP 2 LAST $XR0 251 
J 0
(-5282 4875);
DISPLAY 0.638298 (-5282 4875);
PAINT MONO (-5282 4875);
FORCEPROP 2 LAST CDS_LIB standard
J 0
(-5000 4875);
DISPLAY INVISIBLE (-5000 4875);
FORCEPROP 1 LAST OFFPAGE TRUE
J 0
(-4675 4750);
DISPLAY 0.872340 (-4675 4750);
PAINT GREEN (-4675 4750);
DISPLAY INVISIBLE (-4675 4750);
FORCEPROP 1 LAST COMMENT_BODY TRUE
J 0
(-4875 4775);
DISPLAY 0.872340 (-4875 4775);
PAINT GREEN (-4875 4775);
DISPLAY INVISIBLE (-4875 4775);
FORCEPROP 2 LAST PATH I30
J 0
(-5250 4925);
DISPLAY 0.680851 (-5250 4925);
DISPLAY INVISIBLE (-5250 4925);
FORCEADD OFFPAGE..1
(-5000 4825);
FORCEPROP 2 LAST $XR0 251 
J 0
(-5282 4825);
DISPLAY 0.638298 (-5282 4825);
PAINT MONO (-5282 4825);
FORCEPROP 2 LAST CDS_LIB standard
J 0
(-5000 4825);
DISPLAY INVISIBLE (-5000 4825);
FORCEPROP 1 LAST OFFPAGE TRUE
J 0
(-4675 4700);
DISPLAY 0.872340 (-4675 4700);
PAINT GREEN (-4675 4700);
DISPLAY INVISIBLE (-4675 4700);
FORCEPROP 1 LAST COMMENT_BODY TRUE
J 0
(-4875 4725);
DISPLAY 0.872340 (-4875 4725);
PAINT GREEN (-4875 4725);
DISPLAY INVISIBLE (-4875 4725);
FORCEPROP 2 LAST PATH I31
J 0
(-5250 4875);
DISPLAY 0.680851 (-5250 4875);
DISPLAY INVISIBLE (-5250 4875);
FORCEADD OFFPAGE..4
R 2
(-5000 4775);
FORCEPROP 2 LAST $XR0 251 
J 0
(-5282 4775);
DISPLAY 0.638298 (-5282 4775);
PAINT MONO (-5282 4775);
FORCEPROP 2 LAST CDS_LIB standard
J 2
(-5000 4775);
DISPLAY INVISIBLE (-5000 4775);
FORCEPROP 1 LAST OFFPAGE TRUE
J 2
(-5325 4650);
DISPLAY 0.872340 (-5325 4650);
DISPLAY INVISIBLE (-5325 4650);
FORCEPROP 1 LAST COMMENT_BODY TRUE
J 2
(-4975 4675);
DISPLAY 0.872340 (-4975 4675);
PAINT GREEN (-4975 4675);
DISPLAY INVISIBLE (-4975 4675);
FORCEPROP 2 LAST PATH I32
J 0
(-5250 4825);
DISPLAY 0.680851 (-5250 4825);
DISPLAY INVISIBLE (-5250 4825);
FORCEADD TCA9548APWR..1
(-3925 4550);
FORCEPROP 1 LAST LOCATION U36
J 0
(-4125 5130);
DISPLAY 0.723404 (-4125 5130);
PAINT GREEN (-4125 5130);
FORCEPROP 2 LAST SEC 1
J 0
(-4125 5275);
DISPLAY 0.680851 (-4125 5275);
PAINT MONO (-4125 5275);
DISPLAY INVISIBLE (-4125 5275);
FORCEPROP 2 LASTPIN (-4275 4875) $PN 1
J 2
(-4285 4885);
DISPLAY 0.680851 (-4285 4885);
PAINT MONO (-4285 4885);
FORCEPROP 2 LASTPIN (-4275 4825) $PN 2
J 2
(-4285 4835);
DISPLAY 0.680851 (-4285 4835);
PAINT MONO (-4285 4835);
FORCEPROP 2 LASTPIN (-4275 4775) $PN 21
J 2
(-4285 4785);
DISPLAY 0.680851 (-4285 4785);
PAINT MONO (-4285 4785);
FORCEPROP 2 LASTPIN (-3575 4125) $PN 12
J 0
(-3565 4135);
DISPLAY 0.680851 (-3565 4135);
PAINT MONO (-3565 4135);
FORCEPROP 2 LASTPIN (-4275 4675) $PN 3
J 2
(-4285 4685);
DISPLAY 0.680851 (-4285 4685);
PAINT MONO (-4285 4685);
FORCEPROP 2 LASTPIN (-4275 4525) $PN 5
J 2
(-4285 4535);
DISPLAY 0.680851 (-4285 4535);
PAINT MONO (-4285 4535);
FORCEPROP 2 LASTPIN (-4275 4425) $PN 7
J 2
(-4285 4435);
DISPLAY 0.680851 (-4285 4435);
PAINT MONO (-4285 4435);
FORCEPROP 2 LASTPIN (-4275 4325) $PN 9
J 2
(-4285 4335);
DISPLAY 0.680851 (-4285 4335);
PAINT MONO (-4285 4335);
FORCEPROP 2 LASTPIN (-4275 4225) $PN 11
J 2
(-4285 4235);
DISPLAY 0.680851 (-4285 4235);
PAINT MONO (-4285 4235);
FORCEPROP 2 LASTPIN (-3575 4525) $PN 14
J 0
(-3565 4535);
DISPLAY 0.680851 (-3565 4535);
PAINT MONO (-3565 4535);
FORCEPROP 2 LASTPIN (-3575 4425) $PN 16
J 0
(-3565 4435);
DISPLAY 0.680851 (-3565 4435);
PAINT MONO (-3565 4435);
FORCEPROP 2 LASTPIN (-3575 4325) $PN 18
J 0
(-3565 4335);
DISPLAY 0.680851 (-3565 4335);
PAINT MONO (-3565 4335);
FORCEPROP 2 LASTPIN (-3575 4225) $PN 20
J 0
(-3565 4235);
DISPLAY 0.680851 (-3565 4235);
PAINT MONO (-3565 4235);
FORCEPROP 2 LASTPIN (-3575 4775) $PN 22
J 0
(-3565 4785);
DISPLAY 0.680851 (-3565 4785);
PAINT MONO (-3565 4785);
FORCEPROP 2 LASTPIN (-4275 4575) $PN 4
J 2
(-4285 4585);
DISPLAY 0.680851 (-4285 4585);
PAINT MONO (-4285 4585);
FORCEPROP 2 LASTPIN (-4275 4475) $PN 6
J 2
(-4285 4485);
DISPLAY 0.680851 (-4285 4485);
PAINT MONO (-4285 4485);
FORCEPROP 2 LASTPIN (-4275 4375) $PN 8
J 2
(-4285 4385);
DISPLAY 0.680851 (-4285 4385);
PAINT MONO (-4285 4385);
FORCEPROP 2 LASTPIN (-4275 4275) $PN 10
J 2
(-4285 4285);
DISPLAY 0.680851 (-4285 4285);
PAINT MONO (-4285 4285);
FORCEPROP 2 LASTPIN (-3575 4575) $PN 13
J 0
(-3565 4585);
DISPLAY 0.680851 (-3565 4585);
PAINT MONO (-3565 4585);
FORCEPROP 2 LASTPIN (-3575 4475) $PN 15
J 0
(-3565 4485);
DISPLAY 0.680851 (-3565 4485);
PAINT MONO (-3565 4485);
FORCEPROP 2 LASTPIN (-3575 4375) $PN 17
J 0
(-3565 4385);
DISPLAY 0.680851 (-3565 4385);
PAINT MONO (-3565 4385);
FORCEPROP 2 LASTPIN (-3575 4275) $PN 19
J 0
(-3565 4285);
DISPLAY 0.680851 (-3565 4285);
PAINT MONO (-3565 4285);
FORCEPROP 2 LASTPIN (-3575 4825) $PN 23
J 0
(-3565 4835);
DISPLAY 0.680851 (-3565 4835);
PAINT MONO (-3565 4835);
FORCEPROP 2 LASTPIN (-4275 4975) $PN 24
J 2
(-4285 4985);
DISPLAY 0.680851 (-4285 4985);
PAINT MONO (-4285 4985);
FORCEPROP 2 LAST PART_TYPE SMLF
J 0
(-4125 5225);
DISPLAY 1.021277 (-4125 5225);
FORCEPROP 2 LAST VALUE TCA9548APWR
J 0
(-4125 5175);
DISPLAY 1.021277 (-4125 5175);
FORCEPROP 1 LAST MATERIAL IC
J 0
(-4125 5030);
DISPLAY 0.723404 (-4125 5030);
PAINT GREEN (-4125 5030);
FORCEPROP 2 LAST CDS_LIB pure_quanta
J 0
(-3925 4550);
DISPLAY INVISIBLE (-3925 4550);
FORCEPROP 1 LAST CDS_LMAN_SYM_OUTLINE -200,475,200,-475
J 0
(-3925 4550);
DISPLAY 0.468085 (-3925 4550);
PAINT GREEN (-3925 4550);
DISPLAY INVISIBLE (-3925 4550);
FORCEPROP 2 LAST SEC_TYPE 
J 0
(-4125 5275);
DISPLAY 1.021277 (-4125 5275);
DISPLAY INVISIBLE (-4125 5275);
FORCEPROP 1 LAST NEEDS_NO_SIZE TRUE
J 0
(-3925 4550);
DISPLAY 0.723404 (-3925 4550);
PAINT GREEN (-3925 4550);
DISPLAY INVISIBLE (-3925 4550);
FORCEPROP 1 LAST PATH I33
J 0
(-3925 4550);
DISPLAY 0.723404 (-3925 4550);
PAINT GREEN (-3925 4550);
DISPLAY INVISIBLE (-3925 4550);
FORCEPROP 1 LAST PART_NUMBER AL009548K02
J 0
(-4125 5077);
DISPLAY 0.723404 (-4125 5077);
PAINT GREEN (-4125 5077);
DISPLAY INVISIBLE (-4125 5077);
FORCEADD Q_CAP..1
(-4800 5300);
FORCEPROP 1 LAST LOCATION C106
J 0
(-4750 5400);
DISPLAY 0.978723 (-4750 5400);
FORCEPROP 2 LAST $SEC 1
J 0
(-4750 5500);
DISPLAY 0.680851 (-4750 5500);
PAINT MONO (-4750 5500);
DISPLAY INVISIBLE (-4750 5500);
FORCEPROP 2 LAST CDS_SEC 1
J 0
(-4750 5500);
DISPLAY 1.021277 (-4750 5500);
DISPLAY INVISIBLE (-4750 5500);
FORCEPROP 1 LASTPIN (-4800 5400) $PN 1
J 0
(-4790 5380);
DISPLAY 0.787234 (-4790 5380);
FORCEPROP 1 LASTPIN (-4800 5200) $PN 2
J 0
(-4790 5180);
DISPLAY 0.787234 (-4790 5180);
FORCEPROP 1 LAST VALUE 0.1UF
J 0
(-4750 5350);
DISPLAY 0.510638 (-4750 5350);
FORCEPROP 1 LAST MATERIAL X7R
J 0
(-4750 5200);
DISPLAY 0.510638 (-4750 5200);
FORCEPROP 1 LAST PACK_TYPE 0402
J 0
(-4750 5100);
DISPLAY 0.510638 (-4750 5100);
FORCEPROP 1 LAST VOLTAGE 25V
J 0
(-4750 5300);
DISPLAY 0.510638 (-4750 5300);
FORCEPROP 1 LAST TOLERANCE 10%
J 0
(-4750 5250);
DISPLAY 0.510638 (-4750 5250);
FORCEPROP 2 LAST CDS_LIB pure_quanta
J 2
(-4800 5300);
PAINT MONO (-4800 5300);
DISPLAY INVISIBLE (-4800 5300);
FORCEPROP 1 LAST PATH I34
J 0
(-4750 5450);
DISPLAY 0.978723 (-4750 5450);
PAINT WHITE (-4750 5450);
DISPLAY INVISIBLE (-4750 5450);
FORCEPROP 1 LAST PART_NUMBER CH4104K1B00
J 0
(-4750 5150);
DISPLAY 0.510638 (-4750 5150);
DISPLAY INVISIBLE (-4750 5150);
FORCEADD UNIVERSAL_GND..1
(-4800 5075);
FORCEPROP 3 LASTPIN (-4800 5125) SIG_NAME GND\g
J 0
(-4790 5135);
DISPLAY 0.659574 (-4790 5135);
PAINT MONO (-4790 5135);
DISPLAY INVISIBLE (-4790 5135);
FORCEPROP 2 LAST CDS_LIB pure_quanta_power
J 0
(-4800 5075);
PAINT MONO (-4800 5075);
DISPLAY INVISIBLE (-4800 5075);
FORCEPROP 1 LAST HDL_POWER GND
J 1
(-4775 5000);
DISPLAY 0.872340 (-4775 5000);
PAINT GREEN (-4775 5000);
DISPLAY INVISIBLE (-4775 5000);
FORCEPROP 1 LAST PATH I35
J 0
(-4725 5075);
DISPLAY 0.872340 (-4725 5075);
PAINT AQUA (-4725 5075);
DISPLAY INVISIBLE (-4725 5075);
FORCEADD UNIVERSAL_POWER..1
(-4800 5625);
FORCEPROP 3 LASTPIN (-4800 5575) SIG_NAME P3V3_AUX\g
J 0
(-4790 5585);
DISPLAY 0.659574 (-4790 5585);
PAINT MONO (-4790 5585);
DISPLAY INVISIBLE (-4790 5585);
FORCEPROP 1 LAST HDL_POWER P3V3_AUX
J 1
(-4800 5675);
DISPLAY 0.872340 (-4800 5675);
PAINT GREEN (-4800 5675);
FORCEPROP 2 LAST CDS_LIB pure_quanta_power
J 0
(-4800 5625);
PAINT MONO (-4800 5625);
DISPLAY INVISIBLE (-4800 5625);
FORCEPROP 1 LAST PATH I36
J 0
(-4750 5650);
DISPLAY 0.872340 (-4750 5650);
PAINT AQUA (-4750 5650);
DISPLAY INVISIBLE (-4750 5650);
FORCEADD Q_RES..1
(-2125 575);
FORCEPROP 1 LAST LOCATION R1089
J 0
(-2375 575);
DISPLAY 0.510638 (-2375 575);
FORCEPROP 2 LAST $SEC 1
J 0
(-2175 775);
DISPLAY 0.680851 (-2175 775);
PAINT MONO (-2175 775);
DISPLAY INVISIBLE (-2175 775);
FORCEPROP 2 LAST CDS_SEC 1
J 0
(-2175 775);
DISPLAY 1.021277 (-2175 775);
DISPLAY INVISIBLE (-2175 775);
FORCEPROP 1 LASTPIN (-2225 575) $PN 1
J 0
(-2213 587);
DISPLAY 0.787234 (-2213 587);
FORCEPROP 1 LASTPIN (-2025 575) $PN 2
J 0
(-2063 587);
DISPLAY 0.787234 (-2063 587);
FORCEPROP 1 LAST PACK_TYPE 0402LF
J 0
(-2275 700);
DISPLAY 0.510638 (-2275 700);
FORCEPROP 1 LAST MATERIAL CHIP
J 0
(-1825 575);
DISPLAY 0.510638 (-1825 575);
FORCEPROP 1 LAST TOLERANCE 5%
J 0
(-1900 575);
DISPLAY 0.510638 (-1900 575);
FORCEPROP 1 LAST VALUE 2.2K
J 2
(-1900 575);
DISPLAY 0.510638 (-1900 575);
FORCEPROP 1 LAST WATTAGE 1/16W
J 2
(-1975 700);
DISPLAY 0.510638 (-1975 700);
FORCEPROP 2 LAST CDS_LIB pure_quanta
J 0
(-2125 575);
PAINT MONO (-2125 575);
DISPLAY INVISIBLE (-2125 575);
FORCEPROP 1 LAST PATH I37
J 0
(-2175 725);
DISPLAY 0.978723 (-2175 725);
PAINT WHITE (-2175 725);
DISPLAY INVISIBLE (-2175 725);
FORCEPROP 1 LAST PART_NUMBER CS22202JB07
J 0
(-2275 650);
DISPLAY 0.510638 (-2275 650);
DISPLAY INVISIBLE (-2275 650);
FORCEADD Q_RES..1
(-2125 525);
FORCEPROP 1 LAST LOCATION R1090
J 0
(-2375 525);
DISPLAY 0.510638 (-2375 525);
FORCEPROP 2 LAST $SEC 1
J 0
(-2175 725);
DISPLAY 0.680851 (-2175 725);
PAINT MONO (-2175 725);
DISPLAY INVISIBLE (-2175 725);
FORCEPROP 2 LAST CDS_SEC 1
J 0
(-2175 725);
DISPLAY 1.021277 (-2175 725);
DISPLAY INVISIBLE (-2175 725);
FORCEPROP 1 LASTPIN (-2225 525) $PN 1
J 0
(-2213 537);
DISPLAY 0.787234 (-2213 537);
FORCEPROP 1 LASTPIN (-2025 525) $PN 2
J 0
(-2063 537);
DISPLAY 0.787234 (-2063 537);
FORCEPROP 1 LAST TOLERANCE 5%
J 0
(-1900 525);
DISPLAY 0.510638 (-1900 525);
FORCEPROP 1 LAST VALUE 2.2K
J 2
(-1900 525);
DISPLAY 0.510638 (-1900 525);
FORCEPROP 1 LAST MATERIAL CHIP
J 0
(-1825 525);
DISPLAY 0.510638 (-1825 525);
FORCEPROP 2 LAST CDS_LIB pure_quanta
J 0
(-2125 525);
PAINT MONO (-2125 525);
DISPLAY INVISIBLE (-2125 525);
FORCEPROP 1 LAST PACK_TYPE 0402LF
J 0
(-2225 625);
DISPLAY 0.510638 (-2225 625);
DISPLAY INVISIBLE (-2225 625);
FORCEPROP 1 LAST WATTAGE 1/16W
J 2
(-1925 625);
DISPLAY 0.510638 (-1925 625);
DISPLAY INVISIBLE (-1925 625);
FORCEPROP 1 LAST PATH I38
J 0
(-2175 675);
DISPLAY 0.978723 (-2175 675);
PAINT WHITE (-2175 675);
DISPLAY INVISIBLE (-2175 675);
FORCEPROP 1 LAST PART_NUMBER CS22202JB07
J 0
(-2225 575);
DISPLAY 0.510638 (-2225 575);
DISPLAY INVISIBLE (-2225 575);
FORCEADD Q_RES..1
(-2125 850);
FORCEPROP 1 LAST LOCATION R67
J 0
(-2375 850);
DISPLAY 0.510638 (-2375 850);
FORCEPROP 2 LAST $SEC 1
J 0
(-2175 1050);
DISPLAY 0.680851 (-2175 1050);
PAINT MONO (-2175 1050);
DISPLAY INVISIBLE (-2175 1050);
FORCEPROP 2 LAST CDS_SEC 1
J 0
(-2175 1050);
DISPLAY 1.021277 (-2175 1050);
DISPLAY INVISIBLE (-2175 1050);
FORCEPROP 1 LASTPIN (-2225 850) $PN 1
J 0
(-2213 862);
DISPLAY 0.787234 (-2213 862);
FORCEPROP 1 LASTPIN (-2025 850) $PN 2
J 0
(-2063 862);
DISPLAY 0.787234 (-2063 862);
FORCEPROP 1 LAST MATERIAL CHIP
J 0
(-1825 850);
DISPLAY 0.510638 (-1825 850);
FORCEPROP 1 LAST VALUE 2.2K
J 2
(-1900 850);
DISPLAY 0.510638 (-1900 850);
FORCEPROP 1 LAST TOLERANCE 5%
J 0
(-1900 850);
DISPLAY 0.510638 (-1900 850);
FORCEPROP 1 LAST WATTAGE 1/16W
J 2
(-1925 950);
DISPLAY 0.510638 (-1925 950);
DISPLAY INVISIBLE (-1925 950);
FORCEPROP 1 LAST PACK_TYPE 0402LF
J 0
(-2225 950);
DISPLAY 0.510638 (-2225 950);
DISPLAY INVISIBLE (-2225 950);
FORCEPROP 2 LAST CDS_LIB pure_quanta
J 0
(-2125 850);
PAINT MONO (-2125 850);
DISPLAY INVISIBLE (-2125 850);
FORCEPROP 1 LAST PATH I39
J 0
(-2175 1000);
DISPLAY 0.978723 (-2175 1000);
PAINT WHITE (-2175 1000);
DISPLAY INVISIBLE (-2175 1000);
FORCEPROP 1 LAST PART_NUMBER CS22202JB07
J 0
(-2225 900);
DISPLAY 0.510638 (-2225 900);
DISPLAY INVISIBLE (-2225 900);
FORCEADD Q_RES..2
(-5625 2325);
FORCEPROP 1 LAST LOCATION R319
J 0
(-5580 2450);
DISPLAY 0.978723 (-5580 2450);
FORCEPROP 2 LAST $SEC 1
J 0
(-5575 2550);
DISPLAY 0.680851 (-5575 2550);
PAINT MONO (-5575 2550);
DISPLAY INVISIBLE (-5575 2550);
FORCEPROP 2 LAST CDS_SEC 1
J 0
(-5575 2550);
DISPLAY 1.021277 (-5575 2550);
DISPLAY INVISIBLE (-5575 2550);
FORCEPROP 1 LASTPIN (-5625 2425) $PN 1
J 0
(-5620 2387);
DISPLAY 0.787234 (-5620 2387);
FORCEPROP 1 LASTPIN (-5625 2225) $PN 2
J 0
(-5620 2235);
DISPLAY 0.787234 (-5620 2235);
FORCEPROP 1 LAST TOLERANCE 1%
J 0
(-5580 2350);
DISPLAY 0.638298 (-5580 2350);
FORCEPROP 1 LAST WATTAGE 1/16W
J 0
(-5585 2300);
DISPLAY 0.638298 (-5585 2300);
FORCEPROP 1 LAST MATERIAL CHIP
J 0
(-5585 2250);
DISPLAY 0.638298 (-5585 2250);
FORCEPROP 1 LAST VALUE 1K
J 0
(-5580 2400);
DISPLAY 0.638298 (-5580 2400);
FORCEPROP 1 LAST PACK_TYPE 0402LF
J 0
(-5585 2200);
DISPLAY 0.638298 (-5585 2200);
FORCEPROP 2 LAST CDS_LIB pure_quanta
J 0
(-5625 2325);
PAINT MONO (-5625 2325);
DISPLAY INVISIBLE (-5625 2325);
FORCEPROP 1 LAST PATH I4
J 0
(-5575 2500);
DISPLAY 0.978723 (-5575 2500);
PAINT WHITE (-5575 2500);
DISPLAY INVISIBLE (-5575 2500);
FORCEPROP 1 LAST PART_NUMBER CS21002FB06
J 0
(-5585 2200);
DISPLAY 0.510638 (-5585 2200);
DISPLAY INVISIBLE (-5585 2200);
FORCEADD Q_RES..1
(-2125 900);
FORCEPROP 1 LAST LOCATION R66
J 0
(-2375 900);
DISPLAY 0.510638 (-2375 900);
FORCEPROP 2 LAST $SEC 1
J 0
(-2175 1100);
DISPLAY 0.680851 (-2175 1100);
PAINT MONO (-2175 1100);
DISPLAY INVISIBLE (-2175 1100);
FORCEPROP 2 LAST CDS_SEC 1
J 0
(-2175 1100);
DISPLAY 1.021277 (-2175 1100);
DISPLAY INVISIBLE (-2175 1100);
FORCEPROP 1 LASTPIN (-2225 900) $PN 1
J 0
(-2213 912);
DISPLAY 0.787234 (-2213 912);
FORCEPROP 1 LASTPIN (-2025 900) $PN 2
J 0
(-2063 912);
DISPLAY 0.787234 (-2063 912);
FORCEPROP 1 LAST MATERIAL CHIP
J 0
(-1825 900);
DISPLAY 0.510638 (-1825 900);
FORCEPROP 1 LAST PACK_TYPE 0402LF
J 0
(-2275 1025);
DISPLAY 0.510638 (-2275 1025);
FORCEPROP 1 LAST TOLERANCE 5%
J 0
(-1900 900);
DISPLAY 0.510638 (-1900 900);
FORCEPROP 1 LAST VALUE 2.2K
J 2
(-1900 900);
DISPLAY 0.510638 (-1900 900);
FORCEPROP 1 LAST WATTAGE 1/16W
J 2
(-1975 1025);
DISPLAY 0.510638 (-1975 1025);
FORCEPROP 2 LAST CDS_LIB pure_quanta
J 0
(-2125 900);
PAINT MONO (-2125 900);
DISPLAY INVISIBLE (-2125 900);
FORCEPROP 1 LAST PATH I40
J 0
(-2175 1050);
DISPLAY 0.978723 (-2175 1050);
PAINT WHITE (-2175 1050);
DISPLAY INVISIBLE (-2175 1050);
FORCEPROP 1 LAST PART_NUMBER CS22202JB07
J 0
(-2275 975);
DISPLAY 0.510638 (-2275 975);
DISPLAY INVISIBLE (-2275 975);
FORCEADD Q_RES..1
(-2125 1225);
FORCEPROP 1 LAST LOCATION R2984
J 0
(-2375 1225);
DISPLAY 0.510638 (-2375 1225);
FORCEPROP 2 LAST $SEC 1
J 0
(-2175 1425);
DISPLAY 0.680851 (-2175 1425);
PAINT MONO (-2175 1425);
DISPLAY INVISIBLE (-2175 1425);
FORCEPROP 2 LAST CDS_SEC 1
J 0
(-2175 1425);
DISPLAY 1.021277 (-2175 1425);
DISPLAY INVISIBLE (-2175 1425);
FORCEPROP 1 LASTPIN (-2225 1225) $PN 1
J 0
(-2213 1237);
DISPLAY 0.787234 (-2213 1237);
FORCEPROP 1 LASTPIN (-2025 1225) $PN 2
J 0
(-2063 1237);
DISPLAY 0.787234 (-2063 1237);
FORCEPROP 1 LAST MATERIAL CHIP
J 0
(-1825 1225);
DISPLAY 0.510638 (-1825 1225);
FORCEPROP 1 LAST TOLERANCE 5%
J 0
(-1900 1225);
DISPLAY 0.510638 (-1900 1225);
FORCEPROP 1 LAST VALUE 2.2K
J 2
(-1900 1225);
DISPLAY 0.510638 (-1900 1225);
FORCEPROP 1 LAST PACK_TYPE 0402LF
J 0
(-2275 1350);
DISPLAY 0.510638 (-2275 1350);
FORCEPROP 1 LAST WATTAGE 1/16W
J 2
(-1975 1350);
DISPLAY 0.510638 (-1975 1350);
FORCEPROP 2 LAST CDS_LIB pure_quanta
J 0
(-2125 1225);
PAINT MONO (-2125 1225);
DISPLAY INVISIBLE (-2125 1225);
FORCEPROP 1 LAST PATH I41
J 0
(-2175 1375);
DISPLAY 0.978723 (-2175 1375);
PAINT WHITE (-2175 1375);
DISPLAY INVISIBLE (-2175 1375);
FORCEPROP 1 LAST PART_NUMBER CS22202JB07
J 0
(-2275 1300);
DISPLAY 0.510638 (-2275 1300);
DISPLAY INVISIBLE (-2275 1300);
FORCEADD Q_RES..1
(-2125 1175);
FORCEPROP 1 LAST LOCATION R2985
J 0
(-2375 1175);
DISPLAY 0.510638 (-2375 1175);
FORCEPROP 2 LAST $SEC 1
J 0
(-2175 1375);
DISPLAY 0.680851 (-2175 1375);
PAINT MONO (-2175 1375);
DISPLAY INVISIBLE (-2175 1375);
FORCEPROP 2 LAST CDS_SEC 1
J 0
(-2175 1375);
DISPLAY 1.021277 (-2175 1375);
DISPLAY INVISIBLE (-2175 1375);
FORCEPROP 1 LASTPIN (-2225 1175) $PN 1
J 0
(-2213 1187);
DISPLAY 0.787234 (-2213 1187);
FORCEPROP 1 LASTPIN (-2025 1175) $PN 2
J 0
(-2063 1187);
DISPLAY 0.787234 (-2063 1187);
FORCEPROP 1 LAST TOLERANCE 5%
J 0
(-1900 1175);
DISPLAY 0.510638 (-1900 1175);
FORCEPROP 1 LAST MATERIAL CHIP
J 0
(-1825 1175);
DISPLAY 0.510638 (-1825 1175);
FORCEPROP 1 LAST VALUE 2.2K
J 2
(-1900 1175);
DISPLAY 0.510638 (-1900 1175);
FORCEPROP 2 LAST CDS_LIB pure_quanta
J 0
(-2125 1175);
PAINT MONO (-2125 1175);
DISPLAY INVISIBLE (-2125 1175);
FORCEPROP 1 LAST PACK_TYPE 0402LF
J 0
(-2225 1275);
DISPLAY 0.510638 (-2225 1275);
DISPLAY INVISIBLE (-2225 1275);
FORCEPROP 1 LAST WATTAGE 1/16W
J 2
(-1925 1275);
DISPLAY 0.510638 (-1925 1275);
DISPLAY INVISIBLE (-1925 1275);
FORCEPROP 1 LAST PATH I42
J 0
(-2175 1325);
DISPLAY 0.978723 (-2175 1325);
PAINT WHITE (-2175 1325);
DISPLAY INVISIBLE (-2175 1325);
FORCEPROP 1 LAST PART_NUMBER CS22202JB07
J 0
(-2225 1225);
DISPLAY 0.510638 (-2225 1225);
DISPLAY INVISIBLE (-2225 1225);
FORCEADD Q_RES..1
(-2125 1825);
FORCEPROP 1 LAST LOCATION R3536
J 0
(-2375 1825);
DISPLAY 0.510638 (-2375 1825);
FORCEPROP 2 LAST $SEC 1
J 0
(-2175 2025);
DISPLAY 0.680851 (-2175 2025);
PAINT MONO (-2175 2025);
DISPLAY INVISIBLE (-2175 2025);
FORCEPROP 2 LAST CDS_SEC 1
J 0
(-2175 2025);
DISPLAY 1.021277 (-2175 2025);
DISPLAY INVISIBLE (-2175 2025);
FORCEPROP 1 LASTPIN (-2225 1825) $PN 1
J 0
(-2213 1837);
DISPLAY 0.787234 (-2213 1837);
FORCEPROP 1 LASTPIN (-2025 1825) $PN 2
J 0
(-2063 1837);
DISPLAY 0.787234 (-2063 1837);
FORCEPROP 1 LAST VALUE 2.2K
J 2
(-1900 1825);
DISPLAY 0.510638 (-1900 1825);
FORCEPROP 1 LAST TOLERANCE 5%
J 0
(-1900 1825);
DISPLAY 0.510638 (-1900 1825);
FORCEPROP 1 LAST MATERIAL CHIP
J 0
(-1825 1825);
DISPLAY 0.510638 (-1825 1825);
FORCEPROP 2 LAST CDS_LIB pure_quanta
J 0
(-2125 1825);
PAINT MONO (-2125 1825);
DISPLAY INVISIBLE (-2125 1825);
FORCEPROP 1 LAST PACK_TYPE 0402LF
J 0
(-2225 1925);
DISPLAY 0.510638 (-2225 1925);
DISPLAY INVISIBLE (-2225 1925);
FORCEPROP 1 LAST WATTAGE 1/16W
J 2
(-1925 1925);
DISPLAY 0.510638 (-1925 1925);
DISPLAY INVISIBLE (-1925 1925);
FORCEPROP 1 LAST PATH I43
J 0
(-2175 1975);
DISPLAY 0.978723 (-2175 1975);
PAINT WHITE (-2175 1975);
DISPLAY INVISIBLE (-2175 1975);
FORCEPROP 1 LAST PART_NUMBER CS22202JB07
J 0
(-2225 1875);
DISPLAY 0.510638 (-2225 1875);
DISPLAY INVISIBLE (-2225 1875);
FORCEADD Q_RES..1
(-2125 1875);
FORCEPROP 1 LAST LOCATION R3535
J 0
(-2375 1875);
DISPLAY 0.510638 (-2375 1875);
FORCEPROP 2 LAST $SEC 1
J 0
(-2175 2075);
DISPLAY 0.680851 (-2175 2075);
PAINT MONO (-2175 2075);
DISPLAY INVISIBLE (-2175 2075);
FORCEPROP 2 LAST CDS_SEC 1
J 0
(-2175 2075);
DISPLAY 1.021277 (-2175 2075);
DISPLAY INVISIBLE (-2175 2075);
FORCEPROP 1 LASTPIN (-2225 1875) $PN 1
J 0
(-2213 1887);
DISPLAY 0.787234 (-2213 1887);
FORCEPROP 1 LASTPIN (-2025 1875) $PN 2
J 0
(-2063 1887);
DISPLAY 0.787234 (-2063 1887);
FORCEPROP 1 LAST VALUE 2.2K
J 2
(-1900 1875);
DISPLAY 0.510638 (-1900 1875);
FORCEPROP 1 LAST TOLERANCE 5%
J 0
(-1900 1875);
DISPLAY 0.510638 (-1900 1875);
FORCEPROP 1 LAST PACK_TYPE 0402LF
J 0
(-2275 2000);
DISPLAY 0.510638 (-2275 2000);
FORCEPROP 1 LAST WATTAGE 1/16W
J 2
(-1975 2000);
DISPLAY 0.510638 (-1975 2000);
FORCEPROP 1 LAST MATERIAL CHIP
J 0
(-1825 1875);
DISPLAY 0.510638 (-1825 1875);
FORCEPROP 2 LAST CDS_LIB pure_quanta
J 0
(-2125 1875);
PAINT MONO (-2125 1875);
DISPLAY INVISIBLE (-2125 1875);
FORCEPROP 1 LAST PATH I44
J 0
(-2175 2025);
DISPLAY 0.978723 (-2175 2025);
PAINT WHITE (-2175 2025);
DISPLAY INVISIBLE (-2175 2025);
FORCEPROP 1 LAST PART_NUMBER CS22202JB07
J 0
(-2275 1950);
DISPLAY 0.510638 (-2275 1950);
DISPLAY INVISIBLE (-2275 1950);
FORCEADD Q_RES..1
(-2150 2125);
FORCEPROP 1 LAST LOCATION R3583
J 0
(-2400 2125);
DISPLAY 0.510638 (-2400 2125);
FORCEPROP 0 LAST $SEC 1
J 0
(-1775 2175);
DISPLAY INVISIBLE (-1775 2175);
FORCEPROP 0 LAST CDS_SEC 1
J 0
(-1775 2175);
DISPLAY INVISIBLE (-1775 2175);
FORCEPROP 1 LASTPIN (-2250 2125) $PN 1
J 0
(-2238 2137);
DISPLAY 0.787234 (-2238 2137);
PAINT MONO (-2238 2137);
DISPLAY INVISIBLE (-2238 2137);
FORCEPROP 1 LASTPIN (-2050 2125) $PN 2
J 0
(-2088 2137);
DISPLAY 0.787234 (-2088 2137);
PAINT MONO (-2088 2137);
DISPLAY INVISIBLE (-2088 2137);
FORCEPROP 1 LAST MATERIAL CHIP
J 0
(-1775 2125);
DISPLAY 0.638298 (-1775 2125);
FORCEPROP 1 LAST VALUE 2.2K
J 2
(-1875 2125);
DISPLAY 0.638298 (-1875 2125);
FORCEPROP 1 LAST TOLERANCE 5%
J 0
(-1875 2125);
DISPLAY 0.638298 (-1875 2125);
FORCEPROP 1 LAST WATTAGE 1/16W
J 2
(-1950 2225);
DISPLAY 0.510638 (-1950 2225);
DISPLAY INVISIBLE (-1950 2225);
FORCEPROP 1 LAST PACK_TYPE 0402LF
J 0
(-2250 2225);
DISPLAY 0.510638 (-2250 2225);
DISPLAY INVISIBLE (-2250 2225);
FORCEPROP 2 LAST CDS_LIB pure_quanta
J 0
(-2150 2125);
DISPLAY INVISIBLE (-2150 2125);
FORCEPROP 1 LAST PATH I45
J 0
(-2200 2275);
DISPLAY 0.978723 (-2200 2275);
PAINT WHITE (-2200 2275);
DISPLAY INVISIBLE (-2200 2275);
FORCEPROP 1 LAST PART_NUMBER CS22202JB07
J 0
(-2250 2175);
DISPLAY 0.510638 (-2250 2175);
DISPLAY INVISIBLE (-2250 2175);
FORCEADD Q_RES..1
(-2150 2175);
FORCEPROP 1 LAST LOCATION R3582
J 0
(-2400 2175);
DISPLAY 0.510638 (-2400 2175);
FORCEPROP 0 LAST $SEC 1
J 0
(-2000 2325);
DISPLAY INVISIBLE (-2000 2325);
FORCEPROP 0 LAST CDS_SEC 1
J 0
(-2000 2325);
DISPLAY INVISIBLE (-2000 2325);
FORCEPROP 1 LASTPIN (-2250 2175) $PN 1
J 0
(-2238 2187);
DISPLAY 0.787234 (-2238 2187);
PAINT MONO (-2238 2187);
DISPLAY INVISIBLE (-2238 2187);
FORCEPROP 1 LASTPIN (-2050 2175) $PN 2
J 0
(-2088 2187);
DISPLAY 0.787234 (-2088 2187);
PAINT MONO (-2088 2187);
DISPLAY INVISIBLE (-2088 2187);
FORCEPROP 1 LAST PACK_TYPE 0402LF
J 0
(-2300 2300);
DISPLAY 0.510638 (-2300 2300);
FORCEPROP 1 LAST MATERIAL CHIP
J 0
(-1775 2175);
DISPLAY 0.638298 (-1775 2175);
FORCEPROP 1 LAST TOLERANCE 5%
J 0
(-1875 2175);
DISPLAY 0.638298 (-1875 2175);
FORCEPROP 1 LAST WATTAGE 1/16W
J 2
(-2000 2300);
DISPLAY 0.510638 (-2000 2300);
FORCEPROP 1 LAST VALUE 2.2K
J 2
(-1875 2175);
DISPLAY 0.638298 (-1875 2175);
FORCEPROP 2 LAST CDS_LIB pure_quanta
J 0
(-2150 2175);
DISPLAY INVISIBLE (-2150 2175);
FORCEPROP 1 LAST PATH I46
J 0
(-2200 2325);
DISPLAY 0.978723 (-2200 2325);
PAINT WHITE (-2200 2325);
DISPLAY INVISIBLE (-2200 2325);
FORCEPROP 1 LAST PART_NUMBER CS22202JB07
J 0
(-2300 2250);
DISPLAY 0.510638 (-2300 2250);
DISPLAY INVISIBLE (-2300 2250);
FORCEADD Q_RES..1
(-2150 2450);
FORCEPROP 1 LAST LOCATION R3395
J 0
(-2400 2450);
DISPLAY 0.510638 (-2400 2450);
FORCEPROP 0 LAST $SEC 1
J 0
(-2000 2600);
DISPLAY INVISIBLE (-2000 2600);
FORCEPROP 0 LAST CDS_SEC 1
J 0
(-2000 2600);
DISPLAY INVISIBLE (-2000 2600);
FORCEPROP 1 LASTPIN (-2250 2450) $PN 1
J 0
(-2238 2462);
DISPLAY 0.787234 (-2238 2462);
PAINT MONO (-2238 2462);
DISPLAY INVISIBLE (-2238 2462);
FORCEPROP 1 LASTPIN (-2050 2450) $PN 2
J 0
(-2088 2462);
DISPLAY 0.787234 (-2088 2462);
PAINT MONO (-2088 2462);
DISPLAY INVISIBLE (-2088 2462);
FORCEPROP 1 LAST VALUE 2.2K
J 2
(-1875 2450);
DISPLAY 0.638298 (-1875 2450);
FORCEPROP 1 LAST TOLERANCE 5%
J 0
(-1875 2450);
DISPLAY 0.638298 (-1875 2450);
FORCEPROP 1 LAST MATERIAL CHIP
J 0
(-1775 2450);
DISPLAY 0.638298 (-1775 2450);
FORCEPROP 1 LAST WATTAGE 1/16W
J 2
(-2000 2575);
DISPLAY 0.510638 (-2000 2575);
FORCEPROP 1 LAST PACK_TYPE 0402LF
J 0
(-2300 2575);
DISPLAY 0.510638 (-2300 2575);
FORCEPROP 2 LAST CDS_LIB pure_quanta
J 0
(-2150 2450);
DISPLAY INVISIBLE (-2150 2450);
FORCEPROP 1 LAST PATH I47
J 0
(-2200 2600);
DISPLAY 0.978723 (-2200 2600);
PAINT WHITE (-2200 2600);
DISPLAY INVISIBLE (-2200 2600);
FORCEPROP 1 LAST PART_NUMBER CS22202JB07
J 0
(-2300 2525);
DISPLAY 0.510638 (-2300 2525);
DISPLAY INVISIBLE (-2300 2525);
FORCEADD Q_RES..1
(-2150 2400);
FORCEPROP 1 LAST LOCATION R3396
J 0
(-2400 2400);
DISPLAY 0.510638 (-2400 2400);
FORCEPROP 0 LAST $SEC 1
J 0
(-1775 2450);
DISPLAY INVISIBLE (-1775 2450);
FORCEPROP 0 LAST CDS_SEC 1
J 0
(-1775 2450);
DISPLAY INVISIBLE (-1775 2450);
FORCEPROP 1 LASTPIN (-2250 2400) $PN 1
J 0
(-2238 2412);
DISPLAY 0.787234 (-2238 2412);
PAINT MONO (-2238 2412);
DISPLAY INVISIBLE (-2238 2412);
FORCEPROP 1 LASTPIN (-2050 2400) $PN 2
J 0
(-2088 2412);
DISPLAY 0.787234 (-2088 2412);
PAINT MONO (-2088 2412);
DISPLAY INVISIBLE (-2088 2412);
FORCEPROP 1 LAST TOLERANCE 5%
J 0
(-1875 2400);
DISPLAY 0.638298 (-1875 2400);
FORCEPROP 1 LAST MATERIAL CHIP
J 0
(-1775 2400);
DISPLAY 0.638298 (-1775 2400);
FORCEPROP 1 LAST VALUE 2.2K
J 2
(-1875 2400);
DISPLAY 0.638298 (-1875 2400);
FORCEPROP 2 LAST CDS_LIB pure_quanta
J 0
(-2150 2400);
DISPLAY INVISIBLE (-2150 2400);
FORCEPROP 1 LAST PACK_TYPE 0402LF
J 0
(-2250 2500);
DISPLAY 0.510638 (-2250 2500);
DISPLAY INVISIBLE (-2250 2500);
FORCEPROP 1 LAST WATTAGE 1/16W
J 2
(-1950 2500);
DISPLAY 0.510638 (-1950 2500);
DISPLAY INVISIBLE (-1950 2500);
FORCEPROP 1 LAST PATH I48
J 0
(-2200 2550);
DISPLAY 0.978723 (-2200 2550);
PAINT WHITE (-2200 2550);
DISPLAY INVISIBLE (-2200 2550);
FORCEPROP 1 LAST PART_NUMBER CS22202JB07
J 0
(-2250 2450);
DISPLAY 0.510638 (-2250 2450);
DISPLAY INVISIBLE (-2250 2450);
FORCEADD Q_RES..1
(-2150 2775);
FORCEPROP 1 LAST LOCATION R2205
J 0
(-2400 2775);
DISPLAY 0.510638 (-2400 2775);
FORCEPROP 0 LAST $SEC 1
J 0
(-1775 2825);
DISPLAY INVISIBLE (-1775 2825);
FORCEPROP 0 LAST CDS_SEC 1
J 0
(-1775 2825);
DISPLAY INVISIBLE (-1775 2825);
FORCEPROP 1 LASTPIN (-2250 2775) $PN 1
J 0
(-2238 2787);
DISPLAY 0.787234 (-2238 2787);
PAINT MONO (-2238 2787);
DISPLAY INVISIBLE (-2238 2787);
FORCEPROP 1 LASTPIN (-2050 2775) $PN 2
J 0
(-2088 2787);
DISPLAY 0.787234 (-2088 2787);
PAINT MONO (-2088 2787);
DISPLAY INVISIBLE (-2088 2787);
FORCEPROP 1 LAST MATERIAL EMPTY
J 0
(-1775 2775);
DISPLAY 0.638298 (-1775 2775);
PAINT RED (-1775 2775);
FORCEPROP 1 LAST VALUE 2.2K
J 2
(-1875 2775);
DISPLAY 0.638298 (-1875 2775);
FORCEPROP 1 LAST TOLERANCE 5%
J 0
(-1875 2775);
DISPLAY 0.638298 (-1875 2775);
FORCEPROP 1 LAST WATTAGE 1/16W
J 2
(-1950 2875);
DISPLAY 0.510638 (-1950 2875);
DISPLAY INVISIBLE (-1950 2875);
FORCEPROP 1 LAST PACK_TYPE 0402LF
J 0
(-2250 2875);
DISPLAY 0.510638 (-2250 2875);
DISPLAY INVISIBLE (-2250 2875);
FORCEPROP 2 LAST CDS_LIB pure_quanta
J 0
(-2150 2775);
DISPLAY INVISIBLE (-2150 2775);
FORCEPROP 1 LAST PATH I49
J 0
(-2200 2925);
DISPLAY 0.978723 (-2200 2925);
PAINT WHITE (-2200 2925);
DISPLAY INVISIBLE (-2200 2925);
FORCEPROP 1 LAST PART_NUMBER CS22202JB07
J 0
(-2250 2825);
DISPLAY 0.510638 (-2250 2825);
DISPLAY INVISIBLE (-2250 2825);
FORCEADD UNIVERSAL_GND..1
(-5350 2100);
FORCEPROP 3 LASTPIN (-5350 2150) SIG_NAME GND\g
J 0
(-5340 2160);
DISPLAY 0.659574 (-5340 2160);
PAINT MONO (-5340 2160);
DISPLAY INVISIBLE (-5340 2160);
FORCEPROP 2 LAST ROOM IO_SLOT
J 1
(-5575 2175);
DISPLAY 0.744681 (-5575 2175);
FORCEPROP 2 LAST CDS_LIB pure_quanta_power
J 0
(-5350 2100);
PAINT MONO (-5350 2100);
DISPLAY INVISIBLE (-5350 2100);
FORCEPROP 1 LAST HDL_POWER GND
J 1
(-5325 2025);
DISPLAY 0.872340 (-5325 2025);
PAINT GREEN (-5325 2025);
DISPLAY INVISIBLE (-5325 2025);
FORCEPROP 1 LAST PATH I5
J 0
(-5275 2100);
DISPLAY 0.872340 (-5275 2100);
PAINT AQUA (-5275 2100);
DISPLAY INVISIBLE (-5275 2100);
FORCEADD Q_RES..1
(-2150 2825);
FORCEPROP 1 LAST LOCATION R2204
J 0
(-2400 2825);
DISPLAY 0.510638 (-2400 2825);
FORCEPROP 0 LAST $SEC 1
J 0
(-2000 2975);
DISPLAY INVISIBLE (-2000 2975);
FORCEPROP 0 LAST CDS_SEC 1
J 0
(-2000 2975);
DISPLAY INVISIBLE (-2000 2975);
FORCEPROP 1 LASTPIN (-2250 2825) $PN 1
J 0
(-2238 2837);
DISPLAY 0.787234 (-2238 2837);
PAINT MONO (-2238 2837);
DISPLAY INVISIBLE (-2238 2837);
FORCEPROP 1 LASTPIN (-2050 2825) $PN 2
J 0
(-2088 2837);
DISPLAY 0.787234 (-2088 2837);
PAINT MONO (-2088 2837);
DISPLAY INVISIBLE (-2088 2837);
FORCEPROP 1 LAST MATERIAL EMPTY
J 0
(-1775 2825);
DISPLAY 0.638298 (-1775 2825);
PAINT RED (-1775 2825);
FORCEPROP 1 LAST VALUE 2.2K
J 2
(-1875 2825);
DISPLAY 0.638298 (-1875 2825);
FORCEPROP 1 LAST TOLERANCE 5%
J 0
(-1875 2825);
DISPLAY 0.638298 (-1875 2825);
FORCEPROP 1 LAST WATTAGE 1/16W
J 2
(-2000 2950);
DISPLAY 0.510638 (-2000 2950);
FORCEPROP 1 LAST PACK_TYPE 0402LF
J 0
(-2300 2950);
DISPLAY 0.510638 (-2300 2950);
FORCEPROP 2 LAST CDS_LIB pure_quanta
J 0
(-2150 2825);
DISPLAY INVISIBLE (-2150 2825);
FORCEPROP 1 LAST PATH I50
J 0
(-2200 2975);
DISPLAY 0.978723 (-2200 2975);
PAINT WHITE (-2200 2975);
DISPLAY INVISIBLE (-2200 2975);
FORCEPROP 1 LAST PART_NUMBER CS22202JB07
J 0
(-2300 2900);
DISPLAY 0.510638 (-2300 2900);
DISPLAY INVISIBLE (-2300 2900);
FORCEADD UNIVERSAL_POWER..1
(-2575 3025);
FORCEPROP 3 LASTPIN (-2575 2975) SIG_NAME P3V3_AUX\g
J 0
(-2565 2985);
DISPLAY 0.659574 (-2565 2985);
PAINT MONO (-2565 2985);
DISPLAY INVISIBLE (-2565 2985);
FORCEPROP 1 LAST HDL_POWER P3V3_AUX
J 1
(-2575 3075);
DISPLAY 0.872340 (-2575 3075);
PAINT GREEN (-2575 3075);
FORCEPROP 2 LAST CDS_LIB pure_quanta_power
J 0
(-2575 3025);
PAINT MONO (-2575 3025);
DISPLAY INVISIBLE (-2575 3025);
FORCEPROP 1 LAST PATH I51
J 0
(-2525 3050);
DISPLAY 0.872340 (-2525 3050);
PAINT AQUA (-2525 3050);
DISPLAY INVISIBLE (-2525 3050);
FORCEADD OFFPAGE..2
(-725 525);
FORCEPROP 2 LAST $XR1 251 
J 0
(-416 525);
DISPLAY 0.638298 (-416 525);
PAINT MONO (-416 525);
FORCEPROP 2 LAST $XR0 148 
J 0
(-536 525);
DISPLAY 0.638298 (-536 525);
PAINT MONO (-536 525);
FORCEPROP 2 LAST CDS_LIB standard
J 0
(-725 525);
PAINT MONO (-725 525);
DISPLAY INVISIBLE (-725 525);
FORCEPROP 1 LAST OFFPAGE TRUE
J 0
(-400 400);
DISPLAY 0.872340 (-400 400);
PAINT GREEN (-400 400);
DISPLAY INVISIBLE (-400 400);
FORCEPROP 1 LAST COMMENT_BODY TRUE
J 0
(-770 430);
DISPLAY 0.872340 (-770 430);
PAINT GREEN (-770 430);
DISPLAY INVISIBLE (-770 430);
FORCEPROP 2 LAST PATH I52
J 0
(-400 575);
DISPLAY 0.680851 (-400 575);
DISPLAY INVISIBLE (-400 575);
FORCEADD OFFPAGE..2
(-725 575);
FORCEPROP 2 LAST $XR1 148 
J 0
(-416 575);
DISPLAY 0.638298 (-416 575);
PAINT MONO (-416 575);
FORCEPROP 2 LAST $XR0 251 
J 0
(-536 575);
DISPLAY 0.638298 (-536 575);
PAINT MONO (-536 575);
FORCEPROP 2 LAST CDS_LIB standard
J 0
(-725 575);
PAINT MONO (-725 575);
DISPLAY INVISIBLE (-725 575);
FORCEPROP 1 LAST OFFPAGE TRUE
J 0
(-400 450);
DISPLAY 0.872340 (-400 450);
PAINT GREEN (-400 450);
DISPLAY INVISIBLE (-400 450);
FORCEPROP 1 LAST COMMENT_BODY TRUE
J 0
(-770 480);
DISPLAY 0.872340 (-770 480);
PAINT GREEN (-770 480);
DISPLAY INVISIBLE (-770 480);
FORCEPROP 2 LAST PATH I53
J 0
(-400 625);
DISPLAY 0.680851 (-400 625);
DISPLAY INVISIBLE (-400 625);
FORCEADD OFFPAGE..2
(-725 1825);
FORCEPROP 2 LAST $XR1 251 
J 0
(-416 1825);
DISPLAY 0.638298 (-416 1825);
PAINT MONO (-416 1825);
FORCEPROP 2 LAST $XR0 148 
J 0
(-536 1825);
DISPLAY 0.638298 (-536 1825);
PAINT MONO (-536 1825);
FORCEPROP 2 LAST CDS_LIB standard
J 0
(-725 1825);
PAINT MONO (-725 1825);
DISPLAY INVISIBLE (-725 1825);
FORCEPROP 1 LAST OFFPAGE TRUE
J 0
(-400 1700);
DISPLAY 0.872340 (-400 1700);
PAINT GREEN (-400 1700);
DISPLAY INVISIBLE (-400 1700);
FORCEPROP 1 LAST COMMENT_BODY TRUE
J 0
(-770 1730);
DISPLAY 0.872340 (-770 1730);
PAINT GREEN (-770 1730);
DISPLAY INVISIBLE (-770 1730);
FORCEPROP 2 LAST PATH I54
J 0
(-400 1875);
DISPLAY 0.680851 (-400 1875);
DISPLAY INVISIBLE (-400 1875);
FORCEADD OFFPAGE..2
(-725 1225);
FORCEPROP 2 LAST $XR1 251 
J 0
(-416 1225);
DISPLAY 0.638298 (-416 1225);
PAINT MONO (-416 1225);
FORCEPROP 2 LAST $XR0 249 
J 0
(-536 1225);
DISPLAY 0.638298 (-536 1225);
PAINT MONO (-536 1225);
FORCEPROP 2 LAST CDS_LIB standard
J 0
(-725 1225);
PAINT MONO (-725 1225);
DISPLAY INVISIBLE (-725 1225);
FORCEPROP 1 LAST OFFPAGE TRUE
J 0
(-400 1100);
DISPLAY 0.872340 (-400 1100);
PAINT GREEN (-400 1100);
DISPLAY INVISIBLE (-400 1100);
FORCEPROP 1 LAST COMMENT_BODY TRUE
J 0
(-770 1130);
DISPLAY 0.872340 (-770 1130);
PAINT GREEN (-770 1130);
DISPLAY INVISIBLE (-770 1130);
FORCEPROP 2 LAST PATH I55
J 0
(-400 1275);
DISPLAY 0.680851 (-400 1275);
DISPLAY INVISIBLE (-400 1275);
FORCEADD OFFPAGE..2
(-725 1175);
FORCEPROP 2 LAST $XR1 249 
J 0
(-416 1175);
DISPLAY 0.638298 (-416 1175);
PAINT MONO (-416 1175);
FORCEPROP 2 LAST $XR0 251 
J 0
(-536 1175);
DISPLAY 0.638298 (-536 1175);
PAINT MONO (-536 1175);
FORCEPROP 2 LAST CDS_LIB standard
J 0
(-725 1175);
PAINT MONO (-725 1175);
DISPLAY INVISIBLE (-725 1175);
FORCEPROP 1 LAST OFFPAGE TRUE
J 0
(-400 1050);
DISPLAY 0.872340 (-400 1050);
PAINT GREEN (-400 1050);
DISPLAY INVISIBLE (-400 1050);
FORCEPROP 1 LAST COMMENT_BODY TRUE
J 0
(-770 1080);
DISPLAY 0.872340 (-770 1080);
PAINT GREEN (-770 1080);
DISPLAY INVISIBLE (-770 1080);
FORCEPROP 2 LAST PATH I56
J 0
(-400 1225);
DISPLAY 0.680851 (-400 1225);
DISPLAY INVISIBLE (-400 1225);
FORCEADD OFFPAGE..2
(-725 900);
FORCEPROP 2 LAST $XR1 239 
J 0
(-416 900);
DISPLAY 0.638298 (-416 900);
PAINT MONO (-416 900);
FORCEPROP 2 LAST $XR0 251 
J 0
(-536 900);
DISPLAY 0.638298 (-536 900);
PAINT MONO (-536 900);
FORCEPROP 2 LAST CDS_LIB standard
J 0
(-725 900);
PAINT MONO (-725 900);
DISPLAY INVISIBLE (-725 900);
FORCEPROP 1 LAST OFFPAGE TRUE
J 0
(-400 775);
DISPLAY 0.872340 (-400 775);
PAINT GREEN (-400 775);
DISPLAY INVISIBLE (-400 775);
FORCEPROP 1 LAST COMMENT_BODY TRUE
J 0
(-770 805);
DISPLAY 0.872340 (-770 805);
PAINT GREEN (-770 805);
DISPLAY INVISIBLE (-770 805);
FORCEPROP 2 LAST PATH I57
J 0
(-400 950);
DISPLAY 0.680851 (-400 950);
DISPLAY INVISIBLE (-400 950);
FORCEADD OFFPAGE..2
(-725 850);
FORCEPROP 2 LAST $XR1 251 
J 0
(-416 850);
DISPLAY 0.638298 (-416 850);
PAINT MONO (-416 850);
FORCEPROP 2 LAST $XR0 239 
J 0
(-536 850);
DISPLAY 0.638298 (-536 850);
PAINT MONO (-536 850);
FORCEPROP 2 LAST CDS_LIB standard
J 0
(-725 850);
PAINT MONO (-725 850);
DISPLAY INVISIBLE (-725 850);
FORCEPROP 1 LAST OFFPAGE TRUE
J 0
(-400 725);
DISPLAY 0.872340 (-400 725);
PAINT GREEN (-400 725);
DISPLAY INVISIBLE (-400 725);
FORCEPROP 1 LAST COMMENT_BODY TRUE
J 0
(-770 755);
DISPLAY 0.872340 (-770 755);
PAINT GREEN (-770 755);
DISPLAY INVISIBLE (-770 755);
FORCEPROP 2 LAST PATH I58
J 0
(-400 900);
DISPLAY 0.680851 (-400 900);
DISPLAY INVISIBLE (-400 900);
FORCEADD OFFPAGE..2
(-725 1875);
FORCEPROP 2 LAST $XR1 148 
J 0
(-416 1875);
DISPLAY 0.638298 (-416 1875);
PAINT MONO (-416 1875);
FORCEPROP 2 LAST $XR0 251 
J 0
(-536 1875);
DISPLAY 0.638298 (-536 1875);
PAINT MONO (-536 1875);
FORCEPROP 2 LAST CDS_LIB standard
J 0
(-725 1875);
PAINT MONO (-725 1875);
DISPLAY INVISIBLE (-725 1875);
FORCEPROP 1 LAST OFFPAGE TRUE
J 0
(-400 1750);
DISPLAY 0.872340 (-400 1750);
PAINT GREEN (-400 1750);
DISPLAY INVISIBLE (-400 1750);
FORCEPROP 1 LAST COMMENT_BODY TRUE
J 0
(-770 1780);
DISPLAY 0.872340 (-770 1780);
PAINT GREEN (-770 1780);
DISPLAY INVISIBLE (-770 1780);
FORCEPROP 2 LAST PATH I59
J 0
(-400 1925);
DISPLAY 0.680851 (-400 1925);
DISPLAY INVISIBLE (-400 1925);
FORCEADD Q_RES..2
(-5350 2325);
FORCEPROP 1 LAST LOCATION R587
J 0
(-5305 2450);
DISPLAY 0.978723 (-5305 2450);
FORCEPROP 2 LAST $SEC 1
J 0
(-5300 2550);
DISPLAY 0.680851 (-5300 2550);
PAINT MONO (-5300 2550);
DISPLAY INVISIBLE (-5300 2550);
FORCEPROP 2 LAST CDS_SEC 1
J 0
(-5300 2550);
DISPLAY 1.021277 (-5300 2550);
DISPLAY INVISIBLE (-5300 2550);
FORCEPROP 1 LASTPIN (-5350 2425) $PN 1
J 0
(-5345 2387);
DISPLAY 0.787234 (-5345 2387);
FORCEPROP 1 LASTPIN (-5350 2225) $PN 2
J 0
(-5345 2235);
DISPLAY 0.787234 (-5345 2235);
FORCEPROP 1 LAST TOLERANCE 1%
J 0
(-5305 2350);
DISPLAY 0.638298 (-5305 2350);
FORCEPROP 1 LAST PACK_TYPE 0402LF
J 0
(-5310 2150);
DISPLAY 0.638298 (-5310 2150);
FORCEPROP 1 LAST VALUE 1K
J 0
(-5305 2400);
DISPLAY 0.638298 (-5305 2400);
FORCEPROP 1 LAST MATERIAL CHIP
J 0
(-5310 2250);
DISPLAY 0.638298 (-5310 2250);
FORCEPROP 1 LAST WATTAGE 1/16W
J 0
(-5310 2300);
DISPLAY 0.638298 (-5310 2300);
FORCEPROP 2 LAST CDS_LIB pure_quanta
J 0
(-5350 2325);
PAINT MONO (-5350 2325);
DISPLAY INVISIBLE (-5350 2325);
FORCEPROP 1 LAST PATH I6
J 0
(-5300 2500);
DISPLAY 0.978723 (-5300 2500);
PAINT WHITE (-5300 2500);
DISPLAY INVISIBLE (-5300 2500);
FORCEPROP 1 LAST PART_NUMBER CS21002FB06
J 0
(-5310 2200);
DISPLAY 0.510638 (-5310 2200);
DISPLAY INVISIBLE (-5310 2200);
FORCEPROP 1 LAST LOCATION R587
J 0
(-5300 2550);
DISPLAY 1.021277 (-5300 2550);
DISPLAY INVISIBLE (-5300 2550);
FORCEADD OFFPAGE..2
(-750 2125);
FORCEPROP 2 LAST $XR1 246 
J 0
(-441 2125);
DISPLAY 0.638298 (-441 2125);
PAINT MONO (-441 2125);
FORCEPROP 2 LAST $XR0 251 
J 0
(-561 2125);
DISPLAY 0.638298 (-561 2125);
PAINT MONO (-561 2125);
FORCEPROP 2 LAST CDS_LIB standard
J 0
(-750 2125);
PAINT MONO (-750 2125);
DISPLAY INVISIBLE (-750 2125);
FORCEPROP 1 LAST OFFPAGE TRUE
J 0
(-425 2000);
DISPLAY 0.872340 (-425 2000);
PAINT GREEN (-425 2000);
DISPLAY INVISIBLE (-425 2000);
FORCEPROP 1 LAST COMMENT_BODY TRUE
J 0
(-795 2030);
DISPLAY 0.872340 (-795 2030);
PAINT GREEN (-795 2030);
DISPLAY INVISIBLE (-795 2030);
FORCEPROP 2 LAST PATH I60
J 0
(-425 2175);
DISPLAY 0.680851 (-425 2175);
DISPLAY INVISIBLE (-425 2175);
FORCEADD OFFPAGE..2
(-750 2175);
FORCEPROP 2 LAST $XR1 246 
J 0
(-441 2175);
DISPLAY 0.638298 (-441 2175);
PAINT MONO (-441 2175);
FORCEPROP 2 LAST $XR0 251 
J 0
(-561 2175);
DISPLAY 0.638298 (-561 2175);
PAINT MONO (-561 2175);
FORCEPROP 2 LAST CDS_LIB standard
J 0
(-750 2175);
PAINT MONO (-750 2175);
DISPLAY INVISIBLE (-750 2175);
FORCEPROP 1 LAST OFFPAGE TRUE
J 0
(-425 2050);
DISPLAY 0.872340 (-425 2050);
PAINT GREEN (-425 2050);
DISPLAY INVISIBLE (-425 2050);
FORCEPROP 1 LAST COMMENT_BODY TRUE
J 0
(-795 2080);
DISPLAY 0.872340 (-795 2080);
PAINT GREEN (-795 2080);
DISPLAY INVISIBLE (-795 2080);
FORCEPROP 2 LAST PATH I61
J 0
(-425 2225);
DISPLAY 0.680851 (-425 2225);
DISPLAY INVISIBLE (-425 2225);
FORCEADD OFFPAGE..2
(-750 2400);
FORCEPROP 2 LAST $XR1 252 
J 0
(-441 2400);
DISPLAY 0.638298 (-441 2400);
PAINT MONO (-441 2400);
FORCEPROP 2 LAST $XR0 251 
J 0
(-561 2400);
DISPLAY 0.638298 (-561 2400);
PAINT MONO (-561 2400);
FORCEPROP 2 LAST CDS_LIB standard
J 0
(-750 2400);
PAINT MONO (-750 2400);
DISPLAY INVISIBLE (-750 2400);
FORCEPROP 1 LAST OFFPAGE TRUE
J 0
(-425 2275);
DISPLAY 0.872340 (-425 2275);
PAINT GREEN (-425 2275);
DISPLAY INVISIBLE (-425 2275);
FORCEPROP 1 LAST COMMENT_BODY TRUE
J 0
(-795 2305);
DISPLAY 0.872340 (-795 2305);
PAINT GREEN (-795 2305);
DISPLAY INVISIBLE (-795 2305);
FORCEPROP 2 LAST PATH I62
J 0
(-425 2450);
DISPLAY 0.680851 (-425 2450);
DISPLAY INVISIBLE (-425 2450);
FORCEADD OFFPAGE..2
(-750 2450);
FORCEPROP 2 LAST $XR1 252 
J 0
(-441 2450);
DISPLAY 0.638298 (-441 2450);
PAINT MONO (-441 2450);
FORCEPROP 2 LAST $XR0 251 
J 0
(-561 2450);
DISPLAY 0.638298 (-561 2450);
PAINT MONO (-561 2450);
FORCEPROP 2 LAST CDS_LIB standard
J 0
(-750 2450);
PAINT MONO (-750 2450);
DISPLAY INVISIBLE (-750 2450);
FORCEPROP 1 LAST OFFPAGE TRUE
J 0
(-425 2325);
DISPLAY 0.872340 (-425 2325);
PAINT GREEN (-425 2325);
DISPLAY INVISIBLE (-425 2325);
FORCEPROP 1 LAST COMMENT_BODY TRUE
J 0
(-795 2355);
DISPLAY 0.872340 (-795 2355);
PAINT GREEN (-795 2355);
DISPLAY INVISIBLE (-795 2355);
FORCEPROP 2 LAST PATH I63
J 0
(-425 2500);
DISPLAY 0.680851 (-425 2500);
DISPLAY INVISIBLE (-425 2500);
FORCEADD OFFPAGE..2
(-750 2775);
FORCEPROP 2 LAST $XR1 251 
J 0
(-441 2775);
DISPLAY 0.638298 (-441 2775);
PAINT MONO (-441 2775);
FORCEPROP 2 LAST $XR0 150 
J 0
(-561 2775);
DISPLAY 0.638298 (-561 2775);
PAINT MONO (-561 2775);
FORCEPROP 2 LAST CDS_LIB standard
J 0
(-750 2775);
PAINT MONO (-750 2775);
DISPLAY INVISIBLE (-750 2775);
FORCEPROP 1 LAST OFFPAGE TRUE
J 0
(-425 2650);
DISPLAY 0.872340 (-425 2650);
PAINT GREEN (-425 2650);
DISPLAY INVISIBLE (-425 2650);
FORCEPROP 1 LAST COMMENT_BODY TRUE
J 0
(-795 2680);
DISPLAY 0.872340 (-795 2680);
PAINT GREEN (-795 2680);
DISPLAY INVISIBLE (-795 2680);
FORCEPROP 2 LAST PATH I64
J 0
(-425 2825);
DISPLAY 0.680851 (-425 2825);
DISPLAY INVISIBLE (-425 2825);
FORCEADD OFFPAGE..2
(-750 2825);
FORCEPROP 2 LAST $XR1 251 
J 0
(-441 2825);
DISPLAY 0.638298 (-441 2825);
PAINT MONO (-441 2825);
FORCEPROP 2 LAST $XR0 150 
J 0
(-561 2825);
DISPLAY 0.638298 (-561 2825);
PAINT MONO (-561 2825);
FORCEPROP 2 LAST CDS_LIB standard
J 0
(-750 2825);
PAINT MONO (-750 2825);
DISPLAY INVISIBLE (-750 2825);
FORCEPROP 1 LAST OFFPAGE TRUE
J 0
(-425 2700);
DISPLAY 0.872340 (-425 2700);
PAINT GREEN (-425 2700);
DISPLAY INVISIBLE (-425 2700);
FORCEPROP 1 LAST COMMENT_BODY TRUE
J 0
(-795 2730);
DISPLAY 0.872340 (-795 2730);
PAINT GREEN (-795 2730);
DISPLAY INVISIBLE (-795 2730);
FORCEPROP 2 LAST PATH I65
J 0
(-425 2875);
DISPLAY 0.680851 (-425 2875);
DISPLAY INVISIBLE (-425 2875);
FORCEADD UNIVERSAL_GND..1
(-3425 3950);
FORCEPROP 3 LASTPIN (-3425 4000) SIG_NAME GND\g
J 0
(-3415 4010);
DISPLAY 0.659574 (-3415 4010);
PAINT MONO (-3415 4010);
DISPLAY INVISIBLE (-3415 4010);
FORCEPROP 2 LAST CDS_LIB pure_quanta_power
J 0
(-3425 3950);
DISPLAY INVISIBLE (-3425 3950);
FORCEPROP 1 LAST HDL_POWER GND
J 1
(-3400 3875);
DISPLAY 0.872340 (-3400 3875);
PAINT GREEN (-3400 3875);
DISPLAY INVISIBLE (-3400 3875);
FORCEPROP 1 LAST PATH I66
J 0
(-3350 3950);
DISPLAY 0.872340 (-3350 3950);
PAINT AQUA (-3350 3950);
DISPLAY INVISIBLE (-3350 3950);
FORCEADD Q_RES..1
(-2600 4425);
FORCEPROP 1 LAST LOCATION R2565
J 0
(-2825 4425);
DISPLAY 0.510638 (-2825 4425);
FORCEPROP 0 LAST $SEC 1
J 0
(-2825 4475);
DISPLAY INVISIBLE (-2825 4475);
FORCEPROP 0 LAST CDS_SEC 1
J 0
(-2825 4475);
DISPLAY INVISIBLE (-2825 4475);
FORCEPROP 1 LASTPIN (-2700 4425) $PN 1
J 0
(-2688 4437);
DISPLAY 0.787234 (-2688 4437);
PAINT MONO (-2688 4437);
DISPLAY INVISIBLE (-2688 4437);
FORCEPROP 1 LASTPIN (-2500 4425) $PN 2
J 0
(-2538 4437);
DISPLAY 0.787234 (-2538 4437);
PAINT MONO (-2538 4437);
DISPLAY INVISIBLE (-2538 4437);
FORCEPROP 1 LAST VALUE 0
J 2
(-2450 4425);
DISPLAY 0.510638 (-2450 4425);
FORCEPROP 1 LAST MATERIAL CHIP
J 0
(-2350 4425);
DISPLAY 0.510638 (-2350 4425);
FORCEPROP 1 LAST TOLERANCE 5%
J 0
(-2425 4425);
DISPLAY 0.510638 (-2425 4425);
FORCEPROP 2 LAST CDS_LIB pure_quanta
J 0
(-2600 4425);
DISPLAY INVISIBLE (-2600 4425);
FORCEPROP 1 LAST WATTAGE 1/16W
J 2
(-2500 4350);
DISPLAY 0.319149 (-2500 4350);
DISPLAY INVISIBLE (-2500 4350);
FORCEPROP 1 LAST PACK_TYPE 0402LF
J 0
(-2350 4425);
DISPLAY 0.510638 (-2350 4425);
DISPLAY INVISIBLE (-2350 4425);
FORCEPROP 1 LAST PATH I67
J 0
(-2650 4575);
DISPLAY 0.978723 (-2650 4575);
PAINT WHITE (-2650 4575);
DISPLAY INVISIBLE (-2650 4575);
FORCEPROP 1 LAST PART_NUMBER CS00002JB13
J 0
(-2675 4375);
DISPLAY 0.319149 (-2675 4375);
DISPLAY INVISIBLE (-2675 4375);
FORCEADD Q_RES..1
(-2600 4375);
FORCEPROP 1 LAST LOCATION R3581
J 0
(-2825 4375);
DISPLAY 0.510638 (-2825 4375);
FORCEPROP 0 LAST $SEC 1
J 0
(-2825 4425);
DISPLAY INVISIBLE (-2825 4425);
FORCEPROP 0 LAST CDS_SEC 1
J 0
(-2825 4425);
DISPLAY INVISIBLE (-2825 4425);
FORCEPROP 1 LASTPIN (-2700 4375) $PN 1
J 0
(-2688 4387);
DISPLAY 0.787234 (-2688 4387);
PAINT MONO (-2688 4387);
DISPLAY INVISIBLE (-2688 4387);
FORCEPROP 1 LASTPIN (-2500 4375) $PN 2
J 0
(-2538 4387);
DISPLAY 0.787234 (-2538 4387);
PAINT MONO (-2538 4387);
DISPLAY INVISIBLE (-2538 4387);
FORCEPROP 1 LAST MATERIAL CHIP
J 0
(-2350 4375);
DISPLAY 0.510638 (-2350 4375);
FORCEPROP 1 LAST VALUE 0
J 2
(-2450 4375);
DISPLAY 0.510638 (-2450 4375);
FORCEPROP 1 LAST TOLERANCE 5%
J 0
(-2425 4375);
DISPLAY 0.510638 (-2425 4375);
FORCEPROP 2 LAST CDS_LIB pure_quanta
J 0
(-2600 4375);
DISPLAY INVISIBLE (-2600 4375);
FORCEPROP 1 LAST WATTAGE 1/16W
J 2
(-2500 4525);
DISPLAY 0.319149 (-2500 4525);
DISPLAY INVISIBLE (-2500 4525);
FORCEPROP 1 LAST PACK_TYPE 0402LF
J 0
(-2350 4375);
DISPLAY 0.510638 (-2350 4375);
DISPLAY INVISIBLE (-2350 4375);
FORCEPROP 1 LAST PATH I68
J 0
(-2650 4525);
DISPLAY 0.978723 (-2650 4525);
PAINT WHITE (-2650 4525);
DISPLAY INVISIBLE (-2650 4525);
FORCEPROP 1 LAST PART_NUMBER CS00002JB13
J 0
(-2675 4500);
DISPLAY 0.319149 (-2675 4500);
DISPLAY INVISIBLE (-2675 4500);
FORCEADD Q_RES..1
(-2600 4325);
FORCEPROP 1 LAST LOCATION R3580
J 0
(-2825 4325);
DISPLAY 0.510638 (-2825 4325);
FORCEPROP 0 LAST $SEC 1
J 0
(-2825 4375);
DISPLAY INVISIBLE (-2825 4375);
FORCEPROP 0 LAST CDS_SEC 1
J 0
(-2825 4375);
DISPLAY INVISIBLE (-2825 4375);
FORCEPROP 1 LASTPIN (-2700 4325) $PN 1
J 0
(-2688 4337);
DISPLAY 0.787234 (-2688 4337);
PAINT MONO (-2688 4337);
DISPLAY INVISIBLE (-2688 4337);
FORCEPROP 1 LASTPIN (-2500 4325) $PN 2
J 0
(-2538 4337);
DISPLAY 0.787234 (-2538 4337);
PAINT MONO (-2538 4337);
DISPLAY INVISIBLE (-2538 4337);
FORCEPROP 1 LAST MATERIAL CHIP
J 0
(-2350 4325);
DISPLAY 0.510638 (-2350 4325);
FORCEPROP 1 LAST TOLERANCE 5%
J 0
(-2425 4325);
DISPLAY 0.510638 (-2425 4325);
FORCEPROP 1 LAST VALUE 0
J 2
(-2450 4325);
DISPLAY 0.510638 (-2450 4325);
FORCEPROP 2 LAST CDS_LIB pure_quanta
J 0
(-2600 4325);
DISPLAY INVISIBLE (-2600 4325);
FORCEPROP 1 LAST WATTAGE 1/16W
J 2
(-2500 4250);
DISPLAY 0.319149 (-2500 4250);
DISPLAY INVISIBLE (-2500 4250);
FORCEPROP 1 LAST PACK_TYPE 0402LF
J 0
(-2350 4325);
DISPLAY 0.510638 (-2350 4325);
DISPLAY INVISIBLE (-2350 4325);
FORCEPROP 1 LAST PATH I69
J 0
(-2650 4475);
DISPLAY 0.978723 (-2650 4475);
PAINT WHITE (-2650 4475);
DISPLAY INVISIBLE (-2650 4475);
FORCEPROP 1 LAST PART_NUMBER CS00002JB13
J 0
(-2675 4275);
DISPLAY 0.319149 (-2675 4275);
DISPLAY INVISIBLE (-2675 4275);
FORCEADD Q_RES..2
(-5900 2975);
FORCEPROP 1 LAST LOCATION R316
J 0
(-5855 3100);
DISPLAY 0.978723 (-5855 3100);
FORCEPROP 2 LAST $SEC 1
J 0
(-5850 3200);
DISPLAY 0.680851 (-5850 3200);
PAINT MONO (-5850 3200);
DISPLAY INVISIBLE (-5850 3200);
FORCEPROP 2 LAST CDS_SEC 1
J 0
(-5850 3200);
DISPLAY 1.021277 (-5850 3200);
DISPLAY INVISIBLE (-5850 3200);
FORCEPROP 1 LASTPIN (-5900 3075) $PN 1
J 0
(-5895 3037);
DISPLAY 0.787234 (-5895 3037);
FORCEPROP 1 LASTPIN (-5900 2875) $PN 2
J 0
(-5895 2885);
DISPLAY 0.787234 (-5895 2885);
FORCEPROP 1 LAST WATTAGE 1/16W
J 0
(-5860 2950);
DISPLAY 0.638298 (-5860 2950);
FORCEPROP 1 LAST VALUE 10K
J 0
(-5855 3050);
DISPLAY 0.638298 (-5855 3050);
FORCEPROP 1 LAST PACK_TYPE 0402LF
J 0
(-5860 2850);
DISPLAY 0.638298 (-5860 2850);
FORCEPROP 1 LAST TOLERANCE 1%
J 0
(-5855 3000);
DISPLAY 0.638298 (-5855 3000);
FORCEPROP 1 LAST MATERIAL EMPTY
J 0
(-5860 2900);
DISPLAY 0.638298 (-5860 2900);
PAINT RED (-5860 2900);
FORCEPROP 2 LAST CDS_LIB pure_quanta
J 0
(-5900 2975);
PAINT MONO (-5900 2975);
DISPLAY INVISIBLE (-5900 2975);
FORCEPROP 1 LAST PATH I7
J 0
(-5850 3150);
DISPLAY 0.978723 (-5850 3150);
PAINT WHITE (-5850 3150);
DISPLAY INVISIBLE (-5850 3150);
FORCEPROP 1 LAST PART_NUMBER CS31002FB08
J 0
(-5860 2850);
DISPLAY 0.510638 (-5860 2850);
DISPLAY INVISIBLE (-5860 2850);
FORCEADD Q_RES..1
(-2600 4575);
FORCEPROP 1 LAST LOCATION R2704
J 0
(-2825 4575);
DISPLAY 0.510638 (-2825 4575);
FORCEPROP 0 LAST $SEC 1
J 0
(-2825 4625);
DISPLAY INVISIBLE (-2825 4625);
FORCEPROP 0 LAST CDS_SEC 1
J 0
(-2825 4625);
DISPLAY INVISIBLE (-2825 4625);
FORCEPROP 1 LASTPIN (-2700 4575) $PN 1
J 0
(-2688 4587);
DISPLAY 0.787234 (-2688 4587);
PAINT MONO (-2688 4587);
DISPLAY INVISIBLE (-2688 4587);
FORCEPROP 1 LASTPIN (-2500 4575) $PN 2
J 0
(-2538 4587);
DISPLAY 0.787234 (-2538 4587);
PAINT MONO (-2538 4587);
DISPLAY INVISIBLE (-2538 4587);
FORCEPROP 1 LAST VALUE 0
J 2
(-2450 4575);
DISPLAY 0.510638 (-2450 4575);
FORCEPROP 1 LAST TOLERANCE 5%
J 0
(-2425 4575);
DISPLAY 0.510638 (-2425 4575);
FORCEPROP 1 LAST MATERIAL CHIP
J 0
(-2350 4575);
DISPLAY 0.510638 (-2350 4575);
FORCEPROP 1 LAST WATTAGE 1/16W
J 2
(-2425 4475);
DISPLAY 0.510638 (-2425 4475);
DISPLAY INVISIBLE (-2425 4475);
FORCEPROP 1 LAST PACK_TYPE 0402LF
J 0
(-2700 4475);
DISPLAY 0.510638 (-2700 4475);
DISPLAY INVISIBLE (-2700 4475);
FORCEPROP 2 LAST CDS_LIB pure_quanta
J 0
(-2600 4575);
DISPLAY INVISIBLE (-2600 4575);
FORCEPROP 1 LAST PATH I70
J 0
(-2650 4725);
DISPLAY 0.978723 (-2650 4725);
PAINT WHITE (-2650 4725);
DISPLAY INVISIBLE (-2650 4725);
FORCEPROP 1 LAST PART_NUMBER CS00002JB13
J 0
(-2700 4525);
DISPLAY 0.510638 (-2700 4525);
DISPLAY INVISIBLE (-2700 4525);
FORCEADD Q_RES..1
(-2600 4525);
FORCEPROP 1 LAST LOCATION R2703
J 0
(-2825 4525);
DISPLAY 0.510638 (-2825 4525);
FORCEPROP 0 LAST $SEC 1
J 0
(-2825 4575);
DISPLAY INVISIBLE (-2825 4575);
FORCEPROP 0 LAST CDS_SEC 1
J 0
(-2825 4575);
DISPLAY INVISIBLE (-2825 4575);
FORCEPROP 1 LASTPIN (-2700 4525) $PN 1
J 0
(-2688 4537);
DISPLAY 0.787234 (-2688 4537);
PAINT MONO (-2688 4537);
DISPLAY INVISIBLE (-2688 4537);
FORCEPROP 1 LASTPIN (-2500 4525) $PN 2
J 0
(-2538 4537);
DISPLAY 0.787234 (-2538 4537);
PAINT MONO (-2538 4537);
DISPLAY INVISIBLE (-2538 4537);
FORCEPROP 1 LAST TOLERANCE 5%
J 0
(-2425 4525);
DISPLAY 0.510638 (-2425 4525);
FORCEPROP 1 LAST VALUE 0
J 2
(-2450 4525);
DISPLAY 0.510638 (-2450 4525);
FORCEPROP 1 LAST MATERIAL CHIP
J 0
(-2350 4525);
DISPLAY 0.510638 (-2350 4525);
FORCEPROP 2 LAST CDS_LIB pure_quanta
J 0
(-2600 4525);
DISPLAY INVISIBLE (-2600 4525);
FORCEPROP 1 LAST WATTAGE 1/16W
J 2
(-2500 4450);
DISPLAY 0.319149 (-2500 4450);
DISPLAY INVISIBLE (-2500 4450);
FORCEPROP 1 LAST PACK_TYPE 0402LF
J 0
(-2350 4525);
DISPLAY 0.510638 (-2350 4525);
DISPLAY INVISIBLE (-2350 4525);
FORCEPROP 1 LAST PATH I71
J 0
(-2650 4675);
DISPLAY 0.978723 (-2650 4675);
PAINT WHITE (-2650 4675);
DISPLAY INVISIBLE (-2650 4675);
FORCEPROP 1 LAST PART_NUMBER CS00002JB13
J 0
(-2675 4475);
DISPLAY 0.319149 (-2675 4475);
DISPLAY INVISIBLE (-2675 4475);
FORCEADD Q_RES..1
(-2600 4475);
FORCEPROP 1 LAST LOCATION R2566
J 0
(-2825 4475);
DISPLAY 0.510638 (-2825 4475);
FORCEPROP 0 LAST $SEC 1
J 0
(-2825 4525);
DISPLAY INVISIBLE (-2825 4525);
FORCEPROP 0 LAST CDS_SEC 1
J 0
(-2825 4525);
DISPLAY INVISIBLE (-2825 4525);
FORCEPROP 1 LASTPIN (-2700 4475) $PN 1
J 0
(-2688 4487);
DISPLAY 0.787234 (-2688 4487);
PAINT MONO (-2688 4487);
DISPLAY INVISIBLE (-2688 4487);
FORCEPROP 1 LASTPIN (-2500 4475) $PN 2
J 0
(-2538 4487);
DISPLAY 0.787234 (-2538 4487);
PAINT MONO (-2538 4487);
DISPLAY INVISIBLE (-2538 4487);
FORCEPROP 1 LAST VALUE 0
J 2
(-2450 4475);
DISPLAY 0.510638 (-2450 4475);
FORCEPROP 1 LAST MATERIAL CHIP
J 0
(-2350 4475);
DISPLAY 0.510638 (-2350 4475);
FORCEPROP 1 LAST TOLERANCE 5%
J 0
(-2425 4475);
DISPLAY 0.510638 (-2425 4475);
FORCEPROP 1 LAST WATTAGE 1/16W
J 2
(-2500 4625);
DISPLAY 0.319149 (-2500 4625);
DISPLAY INVISIBLE (-2500 4625);
FORCEPROP 1 LAST PACK_TYPE 0402LF
J 0
(-2350 4475);
DISPLAY 0.510638 (-2350 4475);
DISPLAY INVISIBLE (-2350 4475);
FORCEPROP 2 LAST CDS_LIB pure_quanta
J 0
(-2600 4475);
DISPLAY INVISIBLE (-2600 4475);
FORCEPROP 1 LAST PATH I72
J 0
(-2650 4625);
DISPLAY 0.978723 (-2650 4625);
PAINT WHITE (-2650 4625);
DISPLAY INVISIBLE (-2650 4625);
FORCEPROP 1 LAST PART_NUMBER CS00002JB13
J 0
(-2675 4600);
DISPLAY 0.319149 (-2675 4600);
DISPLAY INVISIBLE (-2675 4600);
FORCEADD Q_RES..1
R 2
(-2525 4825);
FORCEPROP 1 LAST LOCATION R55
J 2
(-2300 4825);
DISPLAY 0.510638 (-2300 4825);
FORCEPROP 2 LAST $SEC 1
J 2
(-2475 5025);
DISPLAY 0.680851 (-2475 5025);
PAINT MONO (-2475 5025);
DISPLAY INVISIBLE (-2475 5025);
FORCEPROP 2 LAST CDS_SEC 1
J 2
(-2475 5025);
DISPLAY 1.021277 (-2475 5025);
DISPLAY INVISIBLE (-2475 5025);
FORCEPROP 1 LASTPIN (-2425 4825) $PN 1
J 2
(-2437 4837);
DISPLAY 0.787234 (-2437 4837);
FORCEPROP 1 LASTPIN (-2625 4825) $PN 2
J 2
(-2587 4837);
DISPLAY 0.787234 (-2587 4837);
FORCEPROP 1 LAST VALUE 33.2
J 0
(-2725 4825);
DISPLAY 0.404255 (-2725 4825);
FORCEPROP 1 LAST TOLERANCE 1%
J 2
(-2750 4825);
DISPLAY 0.404255 (-2750 4825);
FORCEPROP 1 LAST MATERIAL CHIP
J 2
(-2800 4825);
DISPLAY 0.404255 (-2800 4825);
FORCEPROP 1 LAST PACK_TYPE 0402LF
J 2
(-2775 4825);
DISPLAY 0.404255 (-2775 4825);
DISPLAY INVISIBLE (-2775 4825);
FORCEPROP 2 LAST CDS_LIB pure_quanta
J 2
(-2525 4825);
PAINT MONO (-2525 4825);
DISPLAY INVISIBLE (-2525 4825);
FORCEPROP 1 LAST WATTAGE 1/16W
J 0
(-2625 4750);
DISPLAY 0.319149 (-2625 4750);
DISPLAY INVISIBLE (-2625 4750);
FORCEPROP 1 LAST PATH I73
J 2
(-2475 4975);
DISPLAY 0.978723 (-2475 4975);
PAINT WHITE (-2475 4975);
DISPLAY INVISIBLE (-2475 4975);
FORCEPROP 1 LAST PART_NUMBER CS03322FB03
J 2
(-2450 4775);
DISPLAY 0.319149 (-2450 4775);
DISPLAY INVISIBLE (-2450 4775);
FORCEADD Q_RES..1
R 2
(-2525 4775);
FORCEPROP 1 LAST LOCATION R65
J 2
(-2300 4775);
DISPLAY 0.510638 (-2300 4775);
FORCEPROP 2 LAST $SEC 1
J 2
(-2475 4975);
DISPLAY 0.680851 (-2475 4975);
PAINT MONO (-2475 4975);
DISPLAY INVISIBLE (-2475 4975);
FORCEPROP 2 LAST CDS_SEC 1
J 2
(-2475 4975);
DISPLAY 1.021277 (-2475 4975);
DISPLAY INVISIBLE (-2475 4975);
FORCEPROP 1 LASTPIN (-2425 4775) $PN 1
J 2
(-2437 4787);
DISPLAY 0.787234 (-2437 4787);
FORCEPROP 1 LASTPIN (-2625 4775) $PN 2
J 2
(-2587 4787);
DISPLAY 0.787234 (-2587 4787);
FORCEPROP 1 LAST MATERIAL CHIP
J 2
(-2800 4775);
DISPLAY 0.404255 (-2800 4775);
FORCEPROP 1 LAST TOLERANCE 1%
J 2
(-2750 4775);
DISPLAY 0.404255 (-2750 4775);
FORCEPROP 1 LAST PACK_TYPE 0402LF
J 2
(-2425 4950);
DISPLAY 0.404255 (-2425 4950);
FORCEPROP 1 LAST WATTAGE 1/16W
J 0
(-2650 4950);
DISPLAY 0.404255 (-2650 4950);
FORCEPROP 1 LAST VALUE 33.2
J 0
(-2725 4775);
DISPLAY 0.404255 (-2725 4775);
FORCEPROP 2 LAST CDS_LIB pure_quanta
J 2
(-2525 4775);
PAINT MONO (-2525 4775);
DISPLAY INVISIBLE (-2525 4775);
FORCEPROP 1 LAST PATH I74
J 2
(-2475 4925);
DISPLAY 0.978723 (-2475 4925);
PAINT WHITE (-2475 4925);
DISPLAY INVISIBLE (-2475 4925);
FORCEPROP 1 LAST PART_NUMBER CS03322FB03
J 2
(-2425 4900);
DISPLAY 0.404255 (-2425 4900);
DISPLAY INVISIBLE (-2425 4900);
FORCEADD OFFPAGE..5
R 2
(-1400 4325);
FORCEPROP 2 LAST $XR1 252 
J 0
(-1091 4325);
DISPLAY 0.638298 (-1091 4325);
PAINT MONO (-1091 4325);
FORCEPROP 2 LAST $XR0 251 
J 0
(-1211 4325);
DISPLAY 0.638298 (-1211 4325);
PAINT MONO (-1211 4325);
FORCEPROP 2 LAST CDS_LIB standard
J 0
(-1400 4325);
DISPLAY INVISIBLE (-1400 4325);
FORCEPROP 1 LAST OFFPAGE TRUE
J 2
(-1725 4200);
DISPLAY 0.872340 (-1725 4200);
DISPLAY INVISIBLE (-1725 4200);
FORCEPROP 1 LAST COMMENT_BODY TRUE
J 2
(-1500 4250);
DISPLAY 0.872340 (-1500 4250);
PAINT GREEN (-1500 4250);
DISPLAY INVISIBLE (-1500 4250);
FORCEPROP 2 LAST PATH I75
J 0
(-1050 4375);
DISPLAY 0.680851 (-1050 4375);
DISPLAY INVISIBLE (-1050 4375);
FORCEADD OFFPAGE..3
(-1400 4375);
FORCEPROP 2 LAST $XR1 252 
J 0
(-1066 4375);
DISPLAY 0.638298 (-1066 4375);
PAINT MONO (-1066 4375);
FORCEPROP 2 LAST $XR0 251 
J 0
(-1186 4375);
DISPLAY 0.638298 (-1186 4375);
PAINT MONO (-1186 4375);
FORCEPROP 2 LAST CDS_LIB standard
J 0
(-1400 4375);
DISPLAY INVISIBLE (-1400 4375);
FORCEPROP 1 LAST OFFPAGE TRUE
J 0
(-1075 4250);
DISPLAY 0.872340 (-1075 4250);
DISPLAY INVISIBLE (-1075 4250);
FORCEPROP 1 LAST COMMENT_BODY TRUE
J 0
(-1450 4275);
DISPLAY 0.872340 (-1450 4275);
PAINT GREEN (-1450 4275);
DISPLAY INVISIBLE (-1450 4275);
FORCEPROP 2 LAST PATH I76
J 0
(-1050 4425);
DISPLAY 0.680851 (-1050 4425);
DISPLAY INVISIBLE (-1050 4425);
FORCEADD OFFPAGE..5
R 2
(-1400 4425);
FORCEPROP 2 LAST $XR1 239 
J 0
(-1091 4425);
DISPLAY 0.638298 (-1091 4425);
PAINT MONO (-1091 4425);
FORCEPROP 2 LAST $XR0 251 
J 0
(-1211 4425);
DISPLAY 0.638298 (-1211 4425);
PAINT MONO (-1211 4425);
FORCEPROP 2 LAST CDS_LIB standard
J 0
(-1400 4425);
DISPLAY INVISIBLE (-1400 4425);
FORCEPROP 1 LAST OFFPAGE TRUE
J 2
(-1725 4300);
DISPLAY 0.872340 (-1725 4300);
DISPLAY INVISIBLE (-1725 4300);
FORCEPROP 1 LAST COMMENT_BODY TRUE
J 2
(-1500 4350);
DISPLAY 0.872340 (-1500 4350);
PAINT GREEN (-1500 4350);
DISPLAY INVISIBLE (-1500 4350);
FORCEPROP 2 LAST PATH I77
J 0
(-1050 4475);
DISPLAY 0.680851 (-1050 4475);
DISPLAY INVISIBLE (-1050 4475);
FORCEADD OFFPAGE..3
(-1400 4475);
FORCEPROP 2 LAST $XR1 251 
J 0
(-1066 4475);
DISPLAY 0.638298 (-1066 4475);
PAINT MONO (-1066 4475);
FORCEPROP 2 LAST $XR0 239 
J 0
(-1186 4475);
DISPLAY 0.638298 (-1186 4475);
PAINT MONO (-1186 4475);
FORCEPROP 2 LAST CDS_LIB standard
J 0
(-1400 4475);
DISPLAY INVISIBLE (-1400 4475);
FORCEPROP 1 LAST OFFPAGE TRUE
J 0
(-1075 4350);
DISPLAY 0.872340 (-1075 4350);
DISPLAY INVISIBLE (-1075 4350);
FORCEPROP 1 LAST COMMENT_BODY TRUE
J 0
(-1450 4375);
DISPLAY 0.872340 (-1450 4375);
PAINT GREEN (-1450 4375);
DISPLAY INVISIBLE (-1450 4375);
FORCEPROP 2 LAST PATH I78
J 0
(-1050 4525);
DISPLAY 0.680851 (-1050 4525);
DISPLAY INVISIBLE (-1050 4525);
FORCEADD OFFPAGE..5
R 2
(-1400 4525);
FORCEPROP 2 LAST $XR1 251 
J 0
(-1091 4525);
DISPLAY 0.638298 (-1091 4525);
PAINT MONO (-1091 4525);
FORCEPROP 2 LAST $XR0 249 
J 0
(-1211 4525);
DISPLAY 0.638298 (-1211 4525);
PAINT MONO (-1211 4525);
FORCEPROP 2 LAST CDS_LIB standard
J 0
(-1400 4525);
DISPLAY INVISIBLE (-1400 4525);
FORCEPROP 1 LAST OFFPAGE TRUE
J 2
(-1725 4400);
DISPLAY 0.872340 (-1725 4400);
DISPLAY INVISIBLE (-1725 4400);
FORCEPROP 1 LAST COMMENT_BODY TRUE
J 2
(-1500 4450);
DISPLAY 0.872340 (-1500 4450);
PAINT GREEN (-1500 4450);
DISPLAY INVISIBLE (-1500 4450);
FORCEPROP 2 LAST PATH I79
J 0
(-1050 4575);
DISPLAY 0.680851 (-1050 4575);
DISPLAY INVISIBLE (-1050 4575);
FORCEADD Q_RES..2
(-5625 2975);
FORCEPROP 1 LAST LOCATION R318
J 0
(-5580 3100);
DISPLAY 0.978723 (-5580 3100);
FORCEPROP 2 LAST $SEC 1
J 0
(-5575 3200);
DISPLAY 0.680851 (-5575 3200);
PAINT MONO (-5575 3200);
DISPLAY INVISIBLE (-5575 3200);
FORCEPROP 2 LAST CDS_SEC 1
J 0
(-5575 3200);
DISPLAY 1.021277 (-5575 3200);
DISPLAY INVISIBLE (-5575 3200);
FORCEPROP 1 LASTPIN (-5625 3075) $PN 1
J 0
(-5620 3037);
DISPLAY 0.787234 (-5620 3037);
FORCEPROP 1 LASTPIN (-5625 2875) $PN 2
J 0
(-5620 2885);
DISPLAY 0.787234 (-5620 2885);
FORCEPROP 1 LAST VALUE 10K
J 0
(-5580 3050);
DISPLAY 0.638298 (-5580 3050);
FORCEPROP 1 LAST WATTAGE 1/16W
J 0
(-5585 2950);
DISPLAY 0.638298 (-5585 2950);
FORCEPROP 1 LAST PACK_TYPE 0402LF
J 0
(-5585 2850);
DISPLAY 0.638298 (-5585 2850);
FORCEPROP 1 LAST TOLERANCE 1%
J 0
(-5580 3000);
DISPLAY 0.638298 (-5580 3000);
FORCEPROP 1 LAST MATERIAL EMPTY
J 0
(-5585 2900);
DISPLAY 0.638298 (-5585 2900);
PAINT RED (-5585 2900);
FORCEPROP 2 LAST CDS_LIB pure_quanta
J 0
(-5625 2975);
PAINT MONO (-5625 2975);
DISPLAY INVISIBLE (-5625 2975);
FORCEPROP 1 LAST PATH I8
J 0
(-5575 3150);
DISPLAY 0.978723 (-5575 3150);
PAINT WHITE (-5575 3150);
DISPLAY INVISIBLE (-5575 3150);
FORCEPROP 1 LAST PART_NUMBER CS31002FB08
J 0
(-5585 2850);
DISPLAY 0.510638 (-5585 2850);
DISPLAY INVISIBLE (-5585 2850);
FORCEADD OFFPAGE..3
(-1400 4575);
FORCEPROP 2 LAST $XR1 249 
J 0
(-1066 4575);
DISPLAY 0.638298 (-1066 4575);
PAINT MONO (-1066 4575);
FORCEPROP 2 LAST $XR0 251 
J 0
(-1186 4575);
DISPLAY 0.638298 (-1186 4575);
PAINT MONO (-1186 4575);
FORCEPROP 2 LAST CDS_LIB standard
J 0
(-1400 4575);
DISPLAY INVISIBLE (-1400 4575);
FORCEPROP 1 LAST OFFPAGE TRUE
J 0
(-1075 4450);
DISPLAY 0.872340 (-1075 4450);
DISPLAY INVISIBLE (-1075 4450);
FORCEPROP 1 LAST COMMENT_BODY TRUE
J 0
(-1450 4475);
DISPLAY 0.872340 (-1450 4475);
PAINT GREEN (-1450 4475);
DISPLAY INVISIBLE (-1450 4475);
FORCEPROP 2 LAST PATH I80
J 0
(-1050 4625);
DISPLAY 0.680851 (-1050 4625);
DISPLAY INVISIBLE (-1050 4625);
FORCEADD OFFPAGE..4
(-1400 4825);
FORCEPROP 2 LAST $XR1 251 
J 0
(-1094 4825);
DISPLAY 0.638298 (-1094 4825);
PAINT MONO (-1094 4825);
FORCEPROP 2 LAST $XR0 150 
J 0
(-1214 4825);
DISPLAY 0.638298 (-1214 4825);
PAINT MONO (-1214 4825);
FORCEPROP 2 LAST CDS_LIB standard
J 0
(-1400 4825);
DISPLAY INVISIBLE (-1400 4825);
FORCEPROP 1 LAST OFFPAGE TRUE
J 0
(-1075 4700);
DISPLAY 0.872340 (-1075 4700);
DISPLAY INVISIBLE (-1075 4700);
FORCEPROP 1 LAST COMMENT_BODY TRUE
J 0
(-1425 4725);
DISPLAY 0.872340 (-1425 4725);
PAINT GREEN (-1425 4725);
DISPLAY INVISIBLE (-1425 4725);
FORCEPROP 2 LAST PATH I81
J 0
(-1225 4900);
DISPLAY 0.680851 (-1225 4900);
DISPLAY INVISIBLE (-1225 4900);
FORCEADD OFFPAGE..3
(-1400 4775);
FORCEPROP 2 LAST $XR1 251 
J 0
(-1066 4775);
DISPLAY 0.638298 (-1066 4775);
PAINT MONO (-1066 4775);
FORCEPROP 2 LAST $XR0 150 
J 0
(-1186 4775);
DISPLAY 0.638298 (-1186 4775);
PAINT MONO (-1186 4775);
FORCEPROP 2 LAST CDS_LIB standard
J 0
(-1400 4775);
DISPLAY INVISIBLE (-1400 4775);
FORCEPROP 1 LAST OFFPAGE TRUE
J 0
(-1075 4650);
DISPLAY 0.872340 (-1075 4650);
PAINT GREEN (-1075 4650);
DISPLAY INVISIBLE (-1075 4650);
FORCEPROP 1 LAST COMMENT_BODY TRUE
J 0
(-1450 4675);
DISPLAY 0.872340 (-1450 4675);
PAINT GREEN (-1450 4675);
DISPLAY INVISIBLE (-1450 4675);
FORCEPROP 2 LAST PATH I82
J 0
(-1200 4850);
DISPLAY 0.680851 (-1200 4850);
DISPLAY INVISIBLE (-1200 4850);
FORCEADD Q_RES..1
R 2
(-5400 4575);
FORCEPROP 1 LAST LOCATION R6200
J 2
(-5175 4575);
DISPLAY 0.510638 (-5175 4575);
FORCEPROP 0 LAST $SEC 1
J 0
(-5175 4600);
DISPLAY 0.680851 (-5175 4600);
PAINT MONO (-5175 4600);
DISPLAY INVISIBLE (-5175 4600);
FORCEPROP 0 LAST CDS_SEC 1
J 0
(-5175 4600);
DISPLAY 0.680851 (-5175 4600);
DISPLAY INVISIBLE (-5175 4600);
FORCEPROP 1 LASTPIN (-5300 4575) $PN 1
J 2
(-5312 4587);
DISPLAY 0.787234 (-5312 4587);
PAINT MONO (-5312 4587);
FORCEPROP 1 LASTPIN (-5500 4575) $PN 2
J 2
(-5462 4587);
DISPLAY 0.787234 (-5462 4587);
PAINT MONO (-5462 4587);
FORCEPROP 1 LAST VALUE 0
J 0
(-5550 4575);
DISPLAY 0.510638 (-5550 4575);
FORCEPROP 1 LAST TOLERANCE 5%
J 2
(-5575 4575);
DISPLAY 0.510638 (-5575 4575);
FORCEPROP 1 LAST MATERIAL CHIP
J 2
(-5650 4575);
DISPLAY 0.510638 (-5650 4575);
FORCEPROP 1 LAST PACK_TYPE 0402LF
J 2
(-5650 4575);
DISPLAY 0.510638 (-5650 4575);
DISPLAY INVISIBLE (-5650 4575);
FORCEPROP 1 LAST WATTAGE 1/16W
J 0
(-5500 4725);
DISPLAY 0.319149 (-5500 4725);
DISPLAY INVISIBLE (-5500 4725);
FORCEPROP 2 LAST CDS_LIB pure_quanta
J 0
(-5400 4575);
DISPLAY INVISIBLE (-5400 4575);
FORCEPROP 1 LAST PATH I83
J 2
(-5350 4725);
DISPLAY 0.978723 (-5350 4725);
PAINT WHITE (-5350 4725);
DISPLAY INVISIBLE (-5350 4725);
FORCEPROP 1 LAST PART_NUMBER CS00002JB13
J 2
(-5325 4700);
DISPLAY 0.319149 (-5325 4700);
DISPLAY INVISIBLE (-5325 4700);
FORCEADD Q_RES..1
R 2
(-5400 4525);
FORCEPROP 1 LAST LOCATION R6201
J 2
(-5175 4525);
DISPLAY 0.510638 (-5175 4525);
FORCEPROP 0 LAST $SEC 1
J 0
(-5175 4550);
DISPLAY 0.680851 (-5175 4550);
PAINT MONO (-5175 4550);
DISPLAY INVISIBLE (-5175 4550);
FORCEPROP 0 LAST CDS_SEC 1
J 0
(-5175 4550);
DISPLAY 0.680851 (-5175 4550);
DISPLAY INVISIBLE (-5175 4550);
FORCEPROP 1 LASTPIN (-5300 4525) $PN 1
J 2
(-5312 4537);
DISPLAY 0.787234 (-5312 4537);
PAINT MONO (-5312 4537);
FORCEPROP 1 LASTPIN (-5500 4525) $PN 2
J 2
(-5462 4537);
DISPLAY 0.787234 (-5462 4537);
PAINT MONO (-5462 4537);
FORCEPROP 1 LAST VALUE 0
J 0
(-5550 4525);
DISPLAY 0.510638 (-5550 4525);
FORCEPROP 1 LAST TOLERANCE 5%
J 2
(-5575 4525);
DISPLAY 0.510638 (-5575 4525);
FORCEPROP 1 LAST MATERIAL CHIP
J 2
(-5650 4525);
DISPLAY 0.510638 (-5650 4525);
FORCEPROP 1 LAST PACK_TYPE 0402LF
J 2
(-5650 4525);
DISPLAY 0.510638 (-5650 4525);
DISPLAY INVISIBLE (-5650 4525);
FORCEPROP 1 LAST WATTAGE 1/16W
J 0
(-5500 4450);
DISPLAY 0.319149 (-5500 4450);
DISPLAY INVISIBLE (-5500 4450);
FORCEPROP 2 LAST CDS_LIB pure_quanta
J 0
(-5400 4525);
DISPLAY INVISIBLE (-5400 4525);
FORCEPROP 1 LAST PATH I84
J 2
(-5350 4675);
DISPLAY 0.978723 (-5350 4675);
PAINT WHITE (-5350 4675);
DISPLAY INVISIBLE (-5350 4675);
FORCEPROP 1 LAST PART_NUMBER CS00002JB13
J 2
(-5325 4475);
DISPLAY 0.319149 (-5325 4475);
DISPLAY INVISIBLE (-5325 4475);
FORCEADD OFFPAGE..5
(-6600 4575);
FORCEPROP 2 LAST $XR3 251 
J 0
(-7245 4575);
DISPLAY 0.638298 (-7245 4575);
PAINT MONO (-7245 4575);
FORCEPROP 2 LAST $XR2 179 
J 0
(-7125 4575);
DISPLAY 0.638298 (-7125 4575);
PAINT MONO (-7125 4575);
FORCEPROP 2 LAST $XR1 178 
J 0
(-7005 4575);
DISPLAY 0.638298 (-7005 4575);
PAINT MONO (-7005 4575);
FORCEPROP 2 LAST $XR0 176 
J 0
(-6885 4575);
DISPLAY 0.638298 (-6885 4575);
PAINT MONO (-6885 4575);
FORCEPROP 2 LAST CDS_LIB standard
J 0
(-6600 4575);
DISPLAY INVISIBLE (-6600 4575);
FORCEPROP 1 LAST OFFPAGE TRUE
J 0
(-6275 4450);
DISPLAY 0.872340 (-6275 4450);
DISPLAY INVISIBLE (-6275 4450);
FORCEPROP 1 LAST COMMENT_BODY TRUE
J 0
(-6500 4500);
DISPLAY 0.872340 (-6500 4500);
PAINT GREEN (-6500 4500);
DISPLAY INVISIBLE (-6500 4500);
FORCEPROP 2 LAST PATH I85
J 0
(-6550 4650);
DISPLAY 0.680851 (-6550 4650);
DISPLAY INVISIBLE (-6550 4650);
FORCEADD OFFPAGE..3
R 2
(-6600 4525);
FORCEPROP 2 LAST $XR3 178 
J 0
(-7270 4525);
DISPLAY 0.638298 (-7270 4525);
PAINT MONO (-7270 4525);
FORCEPROP 2 LAST $XR2 176 
J 0
(-7150 4525);
DISPLAY 0.638298 (-7150 4525);
PAINT MONO (-7150 4525);
FORCEPROP 2 LAST $XR1 251 
J 0
(-7030 4525);
DISPLAY 0.638298 (-7030 4525);
PAINT MONO (-7030 4525);
FORCEPROP 2 LAST $XR0 179 
J 0
(-6910 4525);
DISPLAY 0.638298 (-6910 4525);
PAINT MONO (-6910 4525);
FORCEPROP 2 LAST CDS_LIB standard
J 0
(-6600 4525);
DISPLAY INVISIBLE (-6600 4525);
FORCEPROP 1 LAST OFFPAGE TRUE
J 2
(-6925 4400);
DISPLAY 0.872340 (-6925 4400);
DISPLAY INVISIBLE (-6925 4400);
FORCEPROP 1 LAST COMMENT_BODY TRUE
J 2
(-6550 4425);
DISPLAY 0.872340 (-6550 4425);
PAINT GREEN (-6550 4425);
DISPLAY INVISIBLE (-6550 4425);
FORCEPROP 2 LAST PATH I86
J 0
(-6550 4600);
DISPLAY 0.680851 (-6550 4600);
DISPLAY INVISIBLE (-6550 4600);
FORCEADD Q_RES..1
(-2125 1600);
FORCEPROP 1 LAST LOCATION R6211
J 0
(-2375 1600);
DISPLAY 0.510638 (-2375 1600);
FORCEPROP 0 LAST $SEC 1
J 0
(-1975 1750);
DISPLAY 0.680851 (-1975 1750);
PAINT MONO (-1975 1750);
DISPLAY INVISIBLE (-1975 1750);
FORCEPROP 0 LAST CDS_SEC 1
J 0
(-1975 1750);
DISPLAY 0.680851 (-1975 1750);
DISPLAY INVISIBLE (-1975 1750);
FORCEPROP 1 LASTPIN (-2225 1600) $PN 1
J 0
(-2213 1612);
DISPLAY 0.787234 (-2213 1612);
PAINT MONO (-2213 1612);
FORCEPROP 1 LASTPIN (-2025 1600) $PN 2
J 0
(-2063 1612);
DISPLAY 0.787234 (-2063 1612);
PAINT MONO (-2063 1612);
FORCEPROP 1 LAST MATERIAL CHIP
J 0
(-1825 1600);
DISPLAY 0.510638 (-1825 1600);
FORCEPROP 1 LAST TOLERANCE 5%
J 0
(-1900 1600);
DISPLAY 0.510638 (-1900 1600);
FORCEPROP 1 LAST VALUE 2.2K
J 2
(-1900 1600);
DISPLAY 0.510638 (-1900 1600);
FORCEPROP 1 LAST PACK_TYPE 0402LF
J 0
(-2275 1725);
DISPLAY 0.510638 (-2275 1725);
FORCEPROP 1 LAST WATTAGE 1/16W
J 2
(-1975 1725);
DISPLAY 0.510638 (-1975 1725);
FORCEPROP 2 LAST CDS_LIB pure_quanta
J 0
(-2125 1600);
DISPLAY INVISIBLE (-2125 1600);
FORCEPROP 1 LAST PATH I89
J 0
(-2175 1750);
DISPLAY 0.978723 (-2175 1750);
PAINT WHITE (-2175 1750);
DISPLAY INVISIBLE (-2175 1750);
FORCEPROP 1 LAST PART_NUMBER CS22202JB07
J 0
(-2275 1675);
DISPLAY 0.510638 (-2275 1675);
DISPLAY INVISIBLE (-2275 1675);
FORCEADD UNIVERSAL_POWER..1
(-5900 3350);
FORCEPROP 3 LASTPIN (-5900 3300) SIG_NAME P3V3_AUX\g
J 0
(-5890 3310);
DISPLAY 0.659574 (-5890 3310);
PAINT MONO (-5890 3310);
DISPLAY INVISIBLE (-5890 3310);
FORCEPROP 1 LAST HDL_POWER P3V3_AUX
J 1
(-5900 3400);
DISPLAY 0.872340 (-5900 3400);
PAINT GREEN (-5900 3400);
FORCEPROP 2 LAST CDS_LIB pure_quanta_power
J 0
(-5900 3350);
PAINT MONO (-5900 3350);
DISPLAY INVISIBLE (-5900 3350);
FORCEPROP 1 LAST PATH I9
J 0
(-5850 3375);
DISPLAY 0.872340 (-5850 3375);
PAINT AQUA (-5850 3375);
DISPLAY INVISIBLE (-5850 3375);
FORCEADD Q_RES..1
(-2125 1550);
FORCEPROP 1 LAST LOCATION R6212
J 0
(-2375 1550);
DISPLAY 0.510638 (-2375 1550);
FORCEPROP 0 LAST $SEC 1
J 0
(-1825 1575);
DISPLAY 0.680851 (-1825 1575);
PAINT MONO (-1825 1575);
DISPLAY INVISIBLE (-1825 1575);
FORCEPROP 0 LAST CDS_SEC 1
J 0
(-1825 1575);
DISPLAY 0.680851 (-1825 1575);
DISPLAY INVISIBLE (-1825 1575);
FORCEPROP 1 LASTPIN (-2225 1550) $PN 1
J 0
(-2213 1562);
DISPLAY 0.787234 (-2213 1562);
PAINT MONO (-2213 1562);
FORCEPROP 1 LASTPIN (-2025 1550) $PN 2
J 0
(-2063 1562);
DISPLAY 0.787234 (-2063 1562);
PAINT MONO (-2063 1562);
FORCEPROP 1 LAST MATERIAL CHIP
J 0
(-1825 1550);
DISPLAY 0.510638 (-1825 1550);
FORCEPROP 1 LAST TOLERANCE 5%
J 0
(-1900 1550);
DISPLAY 0.510638 (-1900 1550);
FORCEPROP 1 LAST VALUE 2.2K
J 2
(-1900 1550);
DISPLAY 0.510638 (-1900 1550);
FORCEPROP 1 LAST WATTAGE 1/16W
J 2
(-1925 1650);
DISPLAY 0.510638 (-1925 1650);
DISPLAY INVISIBLE (-1925 1650);
FORCEPROP 1 LAST PACK_TYPE 0402LF
J 0
(-2225 1650);
DISPLAY 0.510638 (-2225 1650);
DISPLAY INVISIBLE (-2225 1650);
FORCEPROP 2 LAST CDS_LIB pure_quanta
J 0
(-2125 1550);
DISPLAY INVISIBLE (-2125 1550);
FORCEPROP 1 LAST PATH I90
J 0
(-2175 1700);
DISPLAY 0.978723 (-2175 1700);
PAINT WHITE (-2175 1700);
DISPLAY INVISIBLE (-2175 1700);
FORCEPROP 1 LAST PART_NUMBER CS22202JB07
J 0
(-2225 1600);
DISPLAY 0.510638 (-2225 1600);
DISPLAY INVISIBLE (-2225 1600);
FORCEADD OFFPAGE..2
(-725 1550);
FORCEPROP 2 LAST $XR3 251 
J 0
(-176 1550);
DISPLAY 0.638298 (-176 1550);
PAINT MONO (-176 1550);
FORCEPROP 2 LAST $XR2 179 
J 0
(-296 1550);
DISPLAY 0.638298 (-296 1550);
PAINT MONO (-296 1550);
FORCEPROP 2 LAST $XR1 178 
J 0
(-416 1550);
DISPLAY 0.638298 (-416 1550);
PAINT MONO (-416 1550);
FORCEPROP 2 LAST $XR0 176 
J 0
(-536 1550);
DISPLAY 0.638298 (-536 1550);
PAINT MONO (-536 1550);
FORCEPROP 2 LAST CDS_LIB standard
J 0
(-725 1550);
DISPLAY INVISIBLE (-725 1550);
FORCEPROP 1 LAST OFFPAGE TRUE
J 0
(-400 1425);
DISPLAY 0.872340 (-400 1425);
PAINT GREEN (-400 1425);
DISPLAY INVISIBLE (-400 1425);
FORCEPROP 1 LAST COMMENT_BODY TRUE
J 0
(-770 1455);
DISPLAY 0.872340 (-770 1455);
PAINT GREEN (-770 1455);
DISPLAY INVISIBLE (-770 1455);
FORCEPROP 2 LAST PATH I91
J 0
(-550 1625);
DISPLAY 0.680851 (-550 1625);
DISPLAY INVISIBLE (-550 1625);
FORCEADD OFFPAGE..2
(-725 1600);
FORCEPROP 2 LAST $XR3 178 
J 0
(-176 1600);
DISPLAY 0.638298 (-176 1600);
PAINT MONO (-176 1600);
FORCEPROP 2 LAST $XR2 176 
J 0
(-296 1600);
DISPLAY 0.638298 (-296 1600);
PAINT MONO (-296 1600);
FORCEPROP 2 LAST $XR1 251 
J 0
(-416 1600);
DISPLAY 0.638298 (-416 1600);
PAINT MONO (-416 1600);
FORCEPROP 2 LAST $XR0 179 
J 0
(-536 1600);
DISPLAY 0.638298 (-536 1600);
PAINT MONO (-536 1600);
FORCEPROP 2 LAST CDS_LIB standard
J 0
(-725 1600);
DISPLAY INVISIBLE (-725 1600);
FORCEPROP 1 LAST OFFPAGE TRUE
J 0
(-400 1475);
DISPLAY 0.872340 (-400 1475);
PAINT GREEN (-400 1475);
DISPLAY INVISIBLE (-400 1475);
FORCEPROP 1 LAST COMMENT_BODY TRUE
J 0
(-770 1505);
DISPLAY 0.872340 (-770 1505);
PAINT GREEN (-770 1505);
DISPLAY INVISIBLE (-770 1505);
FORCEPROP 2 LAST PATH I92
J 0
(-550 1675);
DISPLAY 0.680851 (-550 1675);
DISPLAY INVISIBLE (-550 1675);
FORCEADD DNS..2
(-2125 2825);
PAINT RED (-2125 2825);
FORCEPROP 2 LAST CDS_LIB mstr_misc
J 0
(-2125 2825);
DISPLAY INVISIBLE (-2125 2825);
FORCEPROP 1 LAST COMMENT_BODY TRUE
J 0
(-2125 2825);
DISPLAY INVISIBLE (-2125 2825);
FORCEADD DNS..2
(-2125 2775);
PAINT RED (-2125 2775);
FORCEPROP 2 LAST CDS_LIB mstr_misc
J 0
(-2125 2775);
DISPLAY INVISIBLE (-2125 2775);
FORCEPROP 1 LAST COMMENT_BODY TRUE
J 0
(-2125 2775);
DISPLAY INVISIBLE (-2125 2775);
FORCEADD DNS..2
(-5345 2945);
PAINT RED (-5345 2945);
FORCEPROP 2 LAST CDS_LIB mstr_misc
J 0
(-5345 2945);
PAINT MONO (-5345 2945);
DISPLAY INVISIBLE (-5345 2945);
FORCEPROP 1 LAST COMMENT_BODY TRUE
J 0
(-5345 2945);
DISPLAY INVISIBLE (-5345 2945);
FORCEADD DNS..2
(-5620 2945);
PAINT RED (-5620 2945);
FORCEPROP 2 LAST CDS_LIB mstr_misc
J 0
(-5620 2945);
PAINT MONO (-5620 2945);
DISPLAY INVISIBLE (-5620 2945);
FORCEPROP 1 LAST COMMENT_BODY TRUE
J 0
(-5620 2945);
DISPLAY INVISIBLE (-5620 2945);
FORCEADD DNS..2
(-5895 2945);
PAINT RED (-5895 2945);
FORCEPROP 2 LAST CDS_LIB mstr_misc
J 0
(-5895 2945);
PAINT MONO (-5895 2945);
DISPLAY INVISIBLE (-5895 2945);
FORCEPROP 1 LAST COMMENT_BODY TRUE
J 0
(-5895 2945);
DISPLAY INVISIBLE (-5895 2945);
FORCEADD QUANTA_TITLE_BLOCK_C..1
(0 0);
FORCEPROP 0 LAST CDS_CON_LAST_MODIFIED Thu Sep 14 16:12:35 2023
J 0
(-1885 15);
DISPLAY INVISIBLE (-1885 15);
FORCEPROP 1 LAST CUSTOM_TXT_CDS <CON_LAST_MODIFIED>
J 0
(-1885 15);
DISPLAY 0.978723 (-1885 15);
FORCEPROP 2 LAST CUSTOM_TXT_CDS <XR_PAGE_TITLE>
J 0
(-7890 5250);
DISPLAY 0.638298 (-7890 5250);
PAINT PINK (-7890 5250);
DISPLAY INVISIBLE (-7890 5250);
FORCEPROP 1 LAST CUSTOM_TXT_CDS <NAME_2>
J 0
(-3175 50);
FORCEPROP 1 LAST CUSTOM_TXT_CDS <NAME_1>
J 0
(-3175 175);
FORCEPROP 1 LAST CUSTOM_TXT_CDS <Q_NUMBER>
J 0
(-1403 103);
DISPLAY 1.212766 (-1403 103);
FORCEPROP 1 LAST CUSTOM_TXT_CDS <Q_PROJ>
J 0
(-2382 102);
DISPLAY 1.212766 (-2382 102);
FORCEPROP 1 LAST CUSTOM_TXT_CDS <Q_REV>
J 0
(-184 103);
DISPLAY 1.212766 (-184 103);
FORCEPROP 1 LAST CUSTOM_TXT_CDS <CON_PAGE_NUM> OF <CON_TOTAL_PAGES>
J 0
(-446 18);
DISPLAY 0.978723 (-446 18);
FORCEPROP 1 LAST Q_TITLE SMBUS - PCIE0  SMBUS
J 0
(-9366 26);
DISPLAY 2.446809 (-9366 26);
PAINT GREEN (-9366 26);
FORCEPROP 2 LAST PAGE_BORDER TRUE
J 0
(-7890 5250);
DISPLAY 0.638298 (-7890 5250);
PAINT PINK (-7890 5250);
DISPLAY INVISIBLE (-7890 5250);
FORCEPROP 2 LAST CDS_LIB pure_quanta
J 0
(0 0);
DISPLAY INVISIBLE (0 0);
FORCEPROP 1 LAST CDS_LMAN_SYM_OUTLINE -9475,6775,100,-125
J 0
(0 0);
DISPLAY 0.468085 (0 0);
PAINT GREEN (0 0);
DISPLAY INVISIBLE (0 0);
FORCEPROP 2 LAST CDS_XR_PAGE_TITLE CR-251 : @T6G_MB_LIB.T6G(SCH_1):PAGE251
J 0
(-7890 5250);
DISPLAY 0.638298 (-7890 5250);
PAINT PINK (-7890 5250);
DISPLAY INVISIBLE (-7890 5250);
FORCEPROP 1 LAST Q_DEPT BU9
J 1
(-3763 49);
DISPLAY 1.957447 (-3763 49);
PAINT GREEN (-3763 49);
DISPLAY INVISIBLE (-3763 49);
FORCEPROP 1 LAST COMMENT_BODY TRUE
J 0
(12 -13);
DISPLAY 0.978723 (12 -13);
PAINT GREEN (12 -13);
DISPLAY INVISIBLE (12 -13);
WIRE 16 -1 (-5900 2150)(-5900 2225);
WIRE 16 -1 (-6600 5250)(-6600 5125);
WIRE 16 -1 (-5625 2150)(-5625 2225);
WIRE 16 -1 (-4800 5200)(-4800 5125);
WIRE 16 -1 (-5350 2150)(-5350 2225);
WIRE 16 -1 (-3425 4125)(-3575 4125);
WIRE 16 -1 (-3425 4125)(-3425 4000);
WIRE 16 -1 (-3575 4825)(-2625 4825);
FORCEPROP 0 LAST CDS_PHYS_NET_NAME SMB_PCIE0_3V3AUX_SDA_R
J 0
(-3535 4873);
PAINT MONO (-3535 4873);
DISPLAY INVISIBLE (-3535 4873);
FORCEPROP 2 LAST SIG_NAME SMB_PCIE0_3V3AUX_SDA_R
J 0
(-3410 4835);
DISPLAY 0.510638 (-3410 4835);
PAINT WHITE (-3410 4835);
FORCEPROP 2 LASTPROP $XRERR UNIQUE?
J 0
(-3650 4835);
DISPLAY 0.638298 (-3650 4835);
PAINT MONO (-3650 4835);
DISPLAY INVISIBLE (-3650 4835);
WIRE 16 -1 (-2700 4425)(-3575 4425);
FORCEPROP 0 LAST CDS_PHYS_NET_NAME SMB_FRU_3V3AUX_SCL_R
J 0
(-3535 4473);
PAINT MONO (-3535 4473);
DISPLAY INVISIBLE (-3535 4473);
FORCEPROP 2 LAST SIG_NAME SMB_FRU_3V3AUX_SCL_R
J 0
(-3410 4435);
DISPLAY 0.510638 (-3410 4435);
PAINT WHITE (-3410 4435);
FORCEPROP 2 LASTPROP $XRERR UNIQUE?
J 0
(-3650 4435);
DISPLAY 0.638298 (-3650 4435);
PAINT MONO (-3650 4435);
DISPLAY INVISIBLE (-3650 4435);
WIRE 16 -1 (-3575 4575)(-2700 4575);
FORCEPROP 0 LAST CDS_PHYS_NET_NAME SMB_BMC_SWB_SDA_R4
J 0
(-3535 4623);
PAINT MONO (-3535 4623);
DISPLAY INVISIBLE (-3535 4623);
FORCEPROP 2 LAST SIG_NAME SMB_BMC_SWB_SDA_R4
J 0
(-3410 4585);
DISPLAY 0.510638 (-3410 4585);
PAINT WHITE (-3410 4585);
FORCEPROP 2 LASTPROP $XRERR UNIQUE?
J 0
(-3650 4585);
DISPLAY 0.638298 (-3650 4585);
PAINT MONO (-3650 4585);
DISPLAY INVISIBLE (-3650 4585);
WIRE 16 -1 (-1450 4575)(-2500 4575);
FORCEPROP 0 LAST CDS_PHYS_NET_NAME SMB_BMC_SWB_SDA
J 0
(-3660 4623);
PAINT MONO (-3660 4623);
DISPLAY INVISIBLE (-3660 4623);
FORCEPROP 2 LAST SIG_NAME SMB_BMC_SWB_SDA
J 0
(-2110 4585);
DISPLAY 0.510638 (-2110 4585);
PAINT WHITE (-2110 4585);
WIRE 16 -1 (-1450 4525)(-2500 4525);
FORCEPROP 0 LAST CDS_PHYS_NET_NAME SMB_BMC_SWB_SCL
J 0
(-3660 4573);
PAINT MONO (-3660 4573);
DISPLAY INVISIBLE (-3660 4573);
FORCEPROP 2 LAST SIG_NAME SMB_BMC_SWB_SCL
J 0
(-2110 4535);
DISPLAY 0.510638 (-2110 4535);
PAINT WHITE (-2110 4535);
WIRE 16 -1 (-3575 4775)(-2625 4775);
FORCEPROP 0 LAST CDS_PHYS_NET_NAME SMB_PCIE0_3V3AUX_SCL_R
J 0
(-3535 4823);
PAINT MONO (-3535 4823);
DISPLAY INVISIBLE (-3535 4823);
FORCEPROP 2 LAST SIG_NAME SMB_PCIE0_3V3AUX_SCL_R
J 0
(-3410 4785);
DISPLAY 0.510638 (-3410 4785);
PAINT WHITE (-3410 4785);
FORCEPROP 2 LASTPROP $XRERR UNIQUE?
J 0
(-3650 4785);
DISPLAY 0.638298 (-3650 4785);
PAINT MONO (-3650 4785);
DISPLAY INVISIBLE (-3650 4785);
WIRE 16 -1 (-2425 4775)(-1450 4775);
FORCEPROP 0 LAST CDS_PHYS_NET_NAME SMB_PCIE0_3V3AUX_SCL
J 0
(-2385 4823);
PAINT MONO (-2385 4823);
DISPLAY INVISIBLE (-2385 4823);
FORCEPROP 2 LAST SIG_NAME SMB_PCIE0_3V3AUX_SCL
J 0
(-2110 4785);
DISPLAY 0.510638 (-2110 4785);
PAINT WHITE (-2110 4785);
WIRE 16 -1 (-775 900)(-2025 900);
FORCEPROP 0 LAST CDS_PHYS_NET_NAME SMB_FRU_3V3AUX_SCL
J 0
(-1810 948);
PAINT MONO (-1810 948);
DISPLAY INVISIBLE (-1810 948);
FORCEPROP 2 LAST SIG_NAME SMB_FRU_3V3AUX_SCL
J 0
(-1510 910);
DISPLAY 0.510638 (-1510 910);
PAINT WHITE (-1510 910);
WIRE 16 -1 (-2500 4475)(-1450 4475);
FORCEPROP 0 LAST CDS_PHYS_NET_NAME SMB_FRU_3V3AUX_SDA
J 0
(-2460 4523);
PAINT MONO (-2460 4523);
DISPLAY INVISIBLE (-2460 4523);
FORCEPROP 2 LAST SIG_NAME SMB_FRU_3V3AUX_SDA
J 0
(-2110 4485);
DISPLAY 0.510638 (-2110 4485);
PAINT WHITE (-2110 4485);
WIRE 16 -1 (-775 850)(-2025 850);
FORCEPROP 0 LAST CDS_PHYS_NET_NAME SMB_FRU_3V3AUX_SDA
J 0
(-1810 898);
PAINT MONO (-1810 898);
DISPLAY INVISIBLE (-1810 898);
FORCEPROP 2 LAST SIG_NAME SMB_FRU_3V3AUX_SDA
J 0
(-1510 860);
DISPLAY 0.510638 (-1510 860);
PAINT WHITE (-1510 860);
WIRE 16 -1 (-3575 4525)(-2700 4525);
FORCEPROP 0 LAST CDS_PHYS_NET_NAME SMB_BMC_SWB_SCL_R4
J 0
(-3535 4573);
PAINT MONO (-3535 4573);
DISPLAY INVISIBLE (-3535 4573);
FORCEPROP 2 LAST SIG_NAME SMB_BMC_SWB_SCL_R4
J 0
(-3410 4535);
DISPLAY 0.510638 (-3410 4535);
PAINT WHITE (-3410 4535);
FORCEPROP 2 LASTPROP $XRERR UNIQUE?
J 0
(-3650 4535);
DISPLAY 0.638298 (-3650 4535);
PAINT MONO (-3650 4535);
DISPLAY INVISIBLE (-3650 4535);
WIRE 16 -1 (-2025 1825)(-775 1825);
FORCEPROP 0 LAST CDS_PHYS_NET_NAME SMB_SENSOR_E1S_3V3AUX_SDA
J 0
(-1985 1873);
PAINT MONO (-1985 1873);
DISPLAY INVISIBLE (-1985 1873);
FORCEPROP 2 LAST SIG_NAME SMB_SENSOR_E1S_3V3AUX_SDA
J 0
(-1510 1835);
DISPLAY 0.510638 (-1510 1835);
PAINT WHITE (-1510 1835);
WIRE 16 -1 (-2025 1550)(-775 1550);
FORCEPROP 2 LAST SIG_NAME SMB_USB_CPU0_HUB1_SDA
J 0
(-1585 1560);
DISPLAY 0.680851 (-1585 1560);
WIRE 16 -1 (-2025 1875)(-775 1875);
FORCEPROP 0 LAST CDS_PHYS_NET_NAME SMB_SENSOR_E1S_3V3AUX_SCL
J 0
(-1985 1923);
PAINT MONO (-1985 1923);
DISPLAY INVISIBLE (-1985 1923);
FORCEPROP 2 LAST SIG_NAME SMB_SENSOR_E1S_3V3AUX_SCL
J 0
(-1510 1885);
DISPLAY 0.510638 (-1510 1885);
PAINT WHITE (-1510 1885);
WIRE 16 -1 (-5500 4275)(-6550 4275);
FORCEPROP 0 LAST CDS_PHYS_NET_NAME SMB_SENSOR_E1S_3V3AUX_SDA
J 0
(-7710 4323);
PAINT MONO (-7710 4323);
DISPLAY INVISIBLE (-7710 4323);
FORCEPROP 2 LAST SIG_NAME SMB_SENSOR_E1S_3V3AUX_SDA
J 0
(-6435 4285);
DISPLAY 0.510638 (-6435 4285);
PAINT WHITE (-6435 4285);
WIRE 16 -1 (-5500 4325)(-6550 4325);
FORCEPROP 0 LAST CDS_PHYS_NET_NAME SMB_SENSOR_M2_P0_3V3AUX_SCL
J 0
(-7710 4373);
PAINT MONO (-7710 4373);
DISPLAY INVISIBLE (-7710 4373);
FORCEPROP 2 LAST SIG_NAME SMB_SENSOR_M2_P1_3V3AUX_SCL
J 0
(-6435 4335);
DISPLAY 0.510638 (-6435 4335);
PAINT WHITE (-6435 4335);
WIRE 16 -1 (-5500 4225)(-6550 4225);
FORCEPROP 0 LAST CDS_PHYS_NET_NAME SMB_SENSOR_E1S_3V3AUX_SCL
J 0
(-7710 4273);
PAINT MONO (-7710 4273);
DISPLAY INVISIBLE (-7710 4273);
FORCEPROP 2 LAST SIG_NAME SMB_SENSOR_E1S_3V3AUX_SCL
J 0
(-6435 4235);
DISPLAY 0.510638 (-6435 4235);
PAINT WHITE (-6435 4235);
WIRE 16 -1 (-775 1175)(-2025 1175);
FORCEPROP 0 LAST CDS_PHYS_NET_NAME SMB_BMC_SWB_SDA
J 0
(-1810 1223);
PAINT MONO (-1810 1223);
DISPLAY INVISIBLE (-1810 1223);
FORCEPROP 2 LAST SIG_NAME SMB_BMC_SWB_SDA
J 0
(-1510 1185);
DISPLAY 0.510638 (-1510 1185);
PAINT WHITE (-1510 1185);
WIRE 16 -1 (-5500 4375)(-6550 4375);
FORCEPROP 0 LAST CDS_PHYS_NET_NAME SMB_SENSOR_M2_P0_3V3AUX_SDA
J 0
(-7710 4423);
PAINT MONO (-7710 4423);
DISPLAY INVISIBLE (-7710 4423);
FORCEPROP 2 LAST SIG_NAME SMB_SENSOR_M2_P1_3V3AUX_SDA
J 0
(-6435 4385);
DISPLAY 0.510638 (-6435 4385);
PAINT WHITE (-6435 4385);
WIRE 16 -1 (-6550 4475)(-5500 4475);
FORCEPROP 0 LAST CDS_PHYS_NET_NAME SMB_IOEXP_3V3AUX_SDA
J 0
(-6510 4523);
PAINT MONO (-6510 4523);
DISPLAY INVISIBLE (-6510 4523);
FORCEPROP 2 LAST SIG_NAME SMB_IOEXP_3V3AUX_SDA
J 0
(-6435 4485);
DISPLAY 0.510638 (-6435 4485);
PAINT WHITE (-6435 4485);
WIRE 16 -1 (-6550 4425)(-5500 4425);
FORCEPROP 0 LAST CDS_PHYS_NET_NAME SMB_IOEXP_3V3AUX_SCL
J 0
(-6510 4473);
PAINT MONO (-6510 4473);
DISPLAY INVISIBLE (-6510 4473);
FORCEPROP 2 LAST SIG_NAME SMB_IOEXP_3V3AUX_SCL
J 0
(-6435 4435);
DISPLAY 0.510638 (-6435 4435);
PAINT WHITE (-6435 4435);
WIRE 16 -1 (-6550 4525)(-5500 4525);
FORCEPROP 2 LAST SIG_NAME SMB_USB_CPU0_HUB1_SCL
J 0
(-6510 4535);
DISPLAY 0.553191 (-6510 4535);
WIRE 16 -1 (-2025 525)(-775 525);
FORCEPROP 0 LAST CDS_PHYS_NET_NAME SMB_SENSOR_M2_P0_3V3AUX_SDA
J 0
(-1985 573);
PAINT MONO (-1985 573);
DISPLAY INVISIBLE (-1985 573);
FORCEPROP 2 LAST SIG_NAME SMB_SENSOR_M2_P1_3V3AUX_SDA
J 0
(-1510 535);
DISPLAY 0.510638 (-1510 535);
PAINT WHITE (-1510 535);
WIRE 16 -1 (-775 1225)(-2025 1225);
FORCEPROP 0 LAST CDS_PHYS_NET_NAME SMB_BMC_SWB_SCL
J 0
(-1810 1273);
PAINT MONO (-1810 1273);
DISPLAY INVISIBLE (-1810 1273);
FORCEPROP 2 LAST SIG_NAME SMB_BMC_SWB_SCL
J 0
(-1510 1235);
DISPLAY 0.510638 (-1510 1235);
PAINT WHITE (-1510 1235);
WIRE 16 -1 (-800 2125)(-2050 2125);
FORCEPROP 0 LAST CDS_PHYS_NET_NAME SMB_IOEXP_3V3AUX_SDA
J 0
(-1835 2173);
PAINT MONO (-1835 2173);
DISPLAY INVISIBLE (-1835 2173);
FORCEPROP 2 LAST SIG_NAME SMB_IOEXP_3V3AUX_SDA
J 0
(-1535 2135);
DISPLAY 0.510638 (-1535 2135);
PAINT WHITE (-1535 2135);
WIRE 16 -1 (-800 2450)(-2050 2450);
FORCEPROP 0 LAST CDS_PHYS_NET_NAME SMB_INA230_3V3AUX_SCL
J 0
(-1835 2498);
PAINT MONO (-1835 2498);
DISPLAY INVISIBLE (-1835 2498);
FORCEPROP 2 LAST SIG_NAME SMB_INA230_3V3AUX_SCL
J 0
(-1535 2460);
DISPLAY 0.510638 (-1535 2460);
PAINT WHITE (-1535 2460);
WIRE 16 -1 (-800 2775)(-2050 2775);
FORCEPROP 0 LAST CDS_PHYS_NET_NAME SMB_PCIE0_3V3AUX_SDA
J 0
(-1835 2823);
PAINT MONO (-1835 2823);
DISPLAY INVISIBLE (-1835 2823);
FORCEPROP 2 LAST SIG_NAME SMB_PCIE0_3V3AUX_SDA
J 0
(-1535 2785);
DISPLAY 0.510638 (-1535 2785);
PAINT WHITE (-1535 2785);
WIRE 16 -1 (-800 2175)(-2050 2175);
FORCEPROP 0 LAST CDS_PHYS_NET_NAME SMB_IOEXP_3V3AUX_SCL
J 0
(-1835 2223);
PAINT MONO (-1835 2223);
DISPLAY INVISIBLE (-1835 2223);
FORCEPROP 2 LAST SIG_NAME SMB_IOEXP_3V3AUX_SCL
J 0
(-1535 2185);
DISPLAY 0.510638 (-1535 2185);
PAINT WHITE (-1535 2185);
WIRE 16 -1 (-800 2825)(-2050 2825);
FORCEPROP 0 LAST CDS_PHYS_NET_NAME SMB_PCIE0_3V3AUX_SCL
J 0
(-1835 2873);
PAINT MONO (-1835 2873);
DISPLAY INVISIBLE (-1835 2873);
FORCEPROP 2 LAST SIG_NAME SMB_PCIE0_3V3AUX_SCL
J 0
(-1535 2835);
DISPLAY 0.510638 (-1535 2835);
PAINT WHITE (-1535 2835);
WIRE 16 -1 (-2425 4825)(-1450 4825);
FORCEPROP 0 LAST CDS_PHYS_NET_NAME SMB_PCIE0_3V3AUX_SDA
J 0
(-2385 4873);
PAINT MONO (-2385 4873);
DISPLAY INVISIBLE (-2385 4873);
FORCEPROP 2 LAST SIG_NAME SMB_PCIE0_3V3AUX_SDA
J 0
(-2110 4835);
DISPLAY 0.510638 (-2110 4835);
PAINT WHITE (-2110 4835);
WIRE 16 -1 (-2025 1600)(-775 1600);
FORCEPROP 2 LAST SIG_NAME SMB_USB_CPU0_HUB1_SCL
J 0
(-1585 1610);
DISPLAY 0.680851 (-1585 1610);
WIRE 16 -1 (-2025 575)(-775 575);
FORCEPROP 0 LAST CDS_PHYS_NET_NAME SMB_SENSOR_M2_P0_3V3AUX_SCL
J 0
(-1985 623);
PAINT MONO (-1985 623);
DISPLAY INVISIBLE (-1985 623);
FORCEPROP 2 LAST SIG_NAME SMB_SENSOR_M2_P1_3V3AUX_SCL
J 0
(-1510 585);
DISPLAY 0.510638 (-1510 585);
PAINT WHITE (-1510 585);
WIRE 16 -1 (-5900 2700)(-4275 2700);
FORCEPROP 2 LAST SIG_NAME PCA9548_PCIE3_ADDR2
J 0
(-5160 2710);
DISPLAY 0.808511 (-5160 2710);
PAINT WHITE (-5160 2710);
WIRE 16 -1 (-5900 2875)(-5900 2700);
WIRE 16 -1 (-5900 2700)(-5900 2425);
WIRE 16 -1 (-5625 2625)(-4275 2625);
FORCEPROP 2 LAST SIG_NAME PCA9548_PCIE3_ADDR1
J 0
(-5160 2635);
DISPLAY 0.808511 (-5160 2635);
PAINT WHITE (-5160 2635);
WIRE 16 -1 (-5625 2875)(-5625 2625);
WIRE 16 -1 (-5625 2625)(-5625 2425);
WIRE 16 -1 (-5350 2550)(-4275 2550);
FORCEPROP 2 LAST SIG_NAME PCA9548_PCIE3_ADDR0
J 0
(-5160 2560);
DISPLAY 0.808511 (-5160 2560);
PAINT WHITE (-5160 2560);
WIRE 16 -1 (-5350 2875)(-5350 2550);
WIRE 16 -1 (-5350 2550)(-5350 2425);
WIRE 16 -1 (-5300 4325)(-4275 4325);
FORCEPROP 0 LAST CDS_PHYS_NET_NAME SMB_PCIE0_3V3AUX_SCL_R3
J 0
(-5260 4373);
PAINT MONO (-5260 4373);
DISPLAY INVISIBLE (-5260 4373);
FORCEPROP 2 LAST SIG_NAME SMB_PCIE0_3V3AUX_SCL_R3
J 0
(-5010 4335);
DISPLAY 0.510638 (-5010 4335);
PAINT WHITE (-5010 4335);
FORCEPROP 2 LASTPROP $XRERR UNIQUE?
J 0
(-5250 4335);
DISPLAY 0.638298 (-5250 4335);
PAINT MONO (-5250 4335);
DISPLAY INVISIBLE (-5250 4335);
WIRE 16 -1 (-5300 4275)(-4275 4275);
FORCEPROP 0 LAST CDS_PHYS_NET_NAME SMB_PCIE0_3V3AUX_SDA_R5
J 0
(-5260 4323);
PAINT MONO (-5260 4323);
DISPLAY INVISIBLE (-5260 4323);
FORCEPROP 2 LAST SIG_NAME SMB_PCIE0_3V3AUX_SDA_R5
J 0
(-5010 4285);
DISPLAY 0.510638 (-5010 4285);
PAINT WHITE (-5010 4285);
FORCEPROP 2 LASTPROP $XRERR UNIQUE?
J 0
(-5250 4285);
DISPLAY 0.638298 (-5250 4285);
PAINT MONO (-5250 4285);
DISPLAY INVISIBLE (-5250 4285);
WIRE 16 -1 (-4950 4875)(-4275 4875);
FORCEPROP 2 LAST SIG_NAME PCA9548_PCIE3_ADDR0
J 0
(-4910 4885);
DISPLAY 0.510638 (-4910 4885);
PAINT WHITE (-4910 4885);
WIRE 16 -1 (-4950 4825)(-4275 4825);
FORCEPROP 2 LAST SIG_NAME PCA9548_PCIE3_ADDR1
J 0
(-4910 4835);
DISPLAY 0.510638 (-4910 4835);
PAINT WHITE (-4910 4835);
WIRE 16 -1 (-4950 4775)(-4275 4775);
FORCEPROP 0 LAST CDS_PHYS_NET_NAME PCA9548_PCIE3_ADDR2
J 0
(-4910 4823);
PAINT MONO (-4910 4823);
DISPLAY INVISIBLE (-4910 4823);
FORCEPROP 2 LAST SIG_NAME PCA9548_PCIE3_ADDR2
J 0
(-4910 4785);
DISPLAY 0.510638 (-4910 4785);
PAINT WHITE (-4910 4785);
WIRE 16 -1 (-4275 4675)(-5400 4675);
FORCEPROP 0 LAST CDS_PHYS_NET_NAME PU_RST_SMB_PCIE0_N
J 0
(-5360 4723);
PAINT MONO (-5360 4723);
DISPLAY INVISIBLE (-5360 4723);
FORCEPROP 2 LAST SIG_NAME PU_RST_SMB_PCIE0_N
J 0
(-4910 4685);
DISPLAY 0.510638 (-4910 4685);
PAINT WHITE (-4910 4685);
FORCEPROP 2 LASTPROP $XRERR UNIQUE?
J 0
(-5150 4685);
DISPLAY 0.638298 (-5150 4685);
PAINT MONO (-5150 4685);
DISPLAY INVISIBLE (-5150 4685);
WIRE 16 -1 (-4275 4575)(-5300 4575);
FORCEPROP 2 LAST SIG_NAME SMB_USB_CPU0_HUB1_SDA_R
J 0
(-5035 4585);
DISPLAY 0.553191 (-5035 4585);
FORCEPROP 2 LASTPROP $XRERR UNIQUE?
J 0
(-5275 4585);
DISPLAY 0.638298 (-5275 4585);
PAINT MONO (-5275 4585);
DISPLAY INVISIBLE (-5275 4585);
WIRE 16 -1 (-4275 4525)(-5300 4525);
FORCEPROP 2 LAST SIG_NAME SMB_USB_CPU0_HUB1_SCL_R
J 0
(-5035 4535);
DISPLAY 0.553191 (-5035 4535);
FORCEPROP 2 LASTPROP $XRERR UNIQUE?
J 0
(-5275 4535);
DISPLAY 0.638298 (-5275 4535);
PAINT MONO (-5275 4535);
DISPLAY INVISIBLE (-5275 4535);
WIRE 16 -1 (-4275 4475)(-5300 4475);
FORCEPROP 0 LAST CDS_PHYS_NET_NAME SMB_IOEXP_3V3AUX_SDA_R
J 0
(-5260 4523);
PAINT MONO (-5260 4523);
DISPLAY INVISIBLE (-5260 4523);
FORCEPROP 2 LAST SIG_NAME SMB_IOEXP_3V3AUX_SDA_R
J 0
(-5010 4485);
DISPLAY 0.510638 (-5010 4485);
PAINT WHITE (-5010 4485);
FORCEPROP 2 LASTPROP $XRERR UNIQUE?
J 0
(-5250 4485);
DISPLAY 0.638298 (-5250 4485);
PAINT MONO (-5250 4485);
DISPLAY INVISIBLE (-5250 4485);
WIRE 16 -1 (-4275 4425)(-5300 4425);
FORCEPROP 0 LAST CDS_PHYS_NET_NAME SMB_IOEXP_3V3AUX_SCL_R
J 0
(-5260 4473);
PAINT MONO (-5260 4473);
DISPLAY INVISIBLE (-5260 4473);
FORCEPROP 2 LAST SIG_NAME SMB_IOEXP_3V3AUX_SCL_R
J 0
(-5010 4435);
DISPLAY 0.510638 (-5010 4435);
PAINT WHITE (-5010 4435);
FORCEPROP 2 LASTPROP $XRERR UNIQUE?
J 0
(-5250 4435);
DISPLAY 0.638298 (-5250 4435);
PAINT MONO (-5250 4435);
DISPLAY INVISIBLE (-5250 4435);
WIRE 16 -1 (-5300 4375)(-4275 4375);
FORCEPROP 0 LAST CDS_PHYS_NET_NAME SMB_PCIE0_3V3AUX_SDA_R3
J 0
(-5260 4423);
PAINT MONO (-5260 4423);
DISPLAY INVISIBLE (-5260 4423);
FORCEPROP 2 LAST SIG_NAME SMB_PCIE0_3V3AUX_SDA_R3
J 0
(-5010 4385);
DISPLAY 0.510638 (-5010 4385);
PAINT WHITE (-5010 4385);
FORCEPROP 2 LASTPROP $XRERR UNIQUE?
J 0
(-5250 4385);
DISPLAY 0.638298 (-5250 4385);
PAINT MONO (-5250 4385);
DISPLAY INVISIBLE (-5250 4385);
WIRE 16 -1 (-5300 4225)(-4275 4225);
FORCEPROP 0 LAST CDS_PHYS_NET_NAME SMB_PCIE0_3V3AUX_SCL_R5
J 0
(-5260 4273);
PAINT MONO (-5260 4273);
DISPLAY INVISIBLE (-5260 4273);
FORCEPROP 2 LAST SIG_NAME SMB_PCIE0_3V3AUX_SCL_R5
J 0
(-5010 4235);
DISPLAY 0.510638 (-5010 4235);
PAINT WHITE (-5010 4235);
FORCEPROP 2 LASTPROP $XRERR UNIQUE?
J 0
(-5250 4235);
DISPLAY 0.638298 (-5250 4235);
PAINT MONO (-5250 4235);
DISPLAY INVISIBLE (-5250 4235);
WIRE 16 -1 (-6550 4575)(-5500 4575);
FORCEPROP 2 LAST SIG_NAME SMB_USB_CPU0_HUB1_SDA
J 0
(-6510 4585);
DISPLAY 0.553191 (-6510 4585);
WIRE 16 -1 (-7075 4675)(-6600 4675);
FORCEPROP 0 LAST CDS_PHYS_NET_NAME RST_SMB_SWITCH_N
J 0
(-7035 4723);
PAINT MONO (-7035 4723);
DISPLAY INVISIBLE (-7035 4723);
FORCEPROP 2 LAST SIG_NAME RST_SMB_SWITCH_N
J 0
(-7060 4685);
DISPLAY 0.510638 (-7060 4685);
PAINT WHITE (-7060 4685);
WIRE 16 -1 (-5600 4675)(-6600 4675);
WIRE 16 -1 (-6600 4925)(-6600 4675);
WIRE 16 -1 (-2500 4425)(-1450 4425);
FORCEPROP 0 LAST CDS_PHYS_NET_NAME SMB_FRU_3V3AUX_SCL
J 0
(-2460 4473);
PAINT MONO (-2460 4473);
DISPLAY INVISIBLE (-2460 4473);
FORCEPROP 2 LAST SIG_NAME SMB_FRU_3V3AUX_SCL
J 0
(-2110 4435);
DISPLAY 0.510638 (-2110 4435);
PAINT WHITE (-2110 4435);
WIRE 16 -1 (-2500 4325)(-1450 4325);
FORCEPROP 0 LAST CDS_PHYS_NET_NAME SMB_INA230_3V3AUX_SCL
J 0
(-2460 4373);
PAINT MONO (-2460 4373);
DISPLAY INVISIBLE (-2460 4373);
FORCEPROP 2 LAST SIG_NAME SMB_INA230_3V3AUX_SCL
J 0
(-2110 4335);
DISPLAY 0.510638 (-2110 4335);
PAINT WHITE (-2110 4335);
WIRE 16 -1 (-2500 4375)(-1450 4375);
FORCEPROP 0 LAST CDS_PHYS_NET_NAME SMB_INA230_3V3AUX_SDA
J 0
(-2460 4423);
PAINT MONO (-2460 4423);
DISPLAY INVISIBLE (-2460 4423);
FORCEPROP 2 LAST SIG_NAME SMB_INA230_3V3AUX_SDA
J 0
(-2110 4385);
DISPLAY 0.510638 (-2110 4385);
PAINT WHITE (-2110 4385);
WIRE 16 -1 (-800 2400)(-2050 2400);
FORCEPROP 0 LAST CDS_PHYS_NET_NAME SMB_INA230_3V3AUX_SDA
J 0
(-1835 2448);
PAINT MONO (-1835 2448);
DISPLAY INVISIBLE (-1835 2448);
FORCEPROP 2 LAST SIG_NAME SMB_INA230_3V3AUX_SDA
J 0
(-1535 2410);
DISPLAY 0.510638 (-1535 2410);
PAINT WHITE (-1535 2410);
WIRE 16 -1 (-2700 4475)(-3575 4475);
FORCEPROP 0 LAST CDS_PHYS_NET_NAME SMB_FRU_3V3AUX_SDA_R
J 0
(-3535 4523);
PAINT MONO (-3535 4523);
DISPLAY INVISIBLE (-3535 4523);
FORCEPROP 2 LAST SIG_NAME SMB_FRU_3V3AUX_SDA_R
J 0
(-3410 4485);
DISPLAY 0.510638 (-3410 4485);
PAINT WHITE (-3410 4485);
FORCEPROP 2 LASTPROP $XRERR UNIQUE?
J 0
(-3650 4485);
DISPLAY 0.638298 (-3650 4485);
PAINT MONO (-3650 4485);
DISPLAY INVISIBLE (-3650 4485);
WIRE 16 -1 (-2700 4375)(-3575 4375);
FORCEPROP 0 LAST CDS_PHYS_NET_NAME SMB_INA230_3V3AUX_SDA_R
J 0
(-3535 4423);
PAINT MONO (-3535 4423);
DISPLAY INVISIBLE (-3535 4423);
FORCEPROP 2 LAST SIG_NAME SMB_INA230_3V3AUX_SDA_R
J 0
(-3410 4385);
DISPLAY 0.510638 (-3410 4385);
PAINT WHITE (-3410 4385);
FORCEPROP 2 LASTPROP $XRERR UNIQUE?
J 0
(-3650 4385);
DISPLAY 0.638298 (-3650 4385);
PAINT MONO (-3650 4385);
DISPLAY INVISIBLE (-3650 4385);
WIRE 16 -1 (-4800 5500)(-4425 5500);
WIRE 16 -1 (-4800 5575)(-4800 5500);
WIRE 16 -1 (-4800 5400)(-4800 5500);
WIRE 16 -1 (-4425 5500)(-4425 4975);
WIRE 16 -1 (-4425 4975)(-4275 4975);
WIRE 16 -1 (-2575 2825)(-2250 2825);
WIRE 16 -1 (-2575 2975)(-2575 2825);
WIRE 16 -1 (-2575 2825)(-2575 2775);
WIRE 16 -1 (-2575 2775)(-2250 2775);
WIRE 16 -1 (-2575 2775)(-2575 2450);
WIRE 16 -1 (-2575 2450)(-2250 2450);
WIRE 16 -1 (-2575 2450)(-2575 2400);
WIRE 16 -1 (-2575 2400)(-2250 2400);
WIRE 16 -1 (-2575 2400)(-2575 2175);
WIRE 16 -1 (-2575 2175)(-2250 2175);
WIRE 16 -1 (-2575 2175)(-2575 2125);
WIRE 16 -1 (-2575 2125)(-2250 2125);
WIRE 16 -1 (-2575 2125)(-2575 1875);
WIRE 16 -1 (-2575 1875)(-2225 1875);
WIRE 16 -1 (-2575 1875)(-2575 1825);
WIRE 16 -1 (-2575 1825)(-2225 1825);
WIRE 16 -1 (-2575 1825)(-2575 1600);
WIRE 16 -1 (-2225 1600)(-2575 1600);
WIRE 16 -1 (-2575 1600)(-2575 1550);
WIRE 16 -1 (-2225 1550)(-2575 1550);
WIRE 16 -1 (-2575 1550)(-2575 1225);
WIRE 16 -1 (-2575 1225)(-2225 1225);
WIRE 16 -1 (-2575 1225)(-2575 1175);
WIRE 16 -1 (-2575 1175)(-2225 1175);
WIRE 16 -1 (-2575 900)(-2575 1175);
WIRE 16 -1 (-2575 900)(-2225 900);
WIRE 16 -1 (-2575 850)(-2575 900);
WIRE 16 -1 (-2575 850)(-2225 850);
WIRE 16 -1 (-2575 575)(-2575 850);
WIRE 16 -1 (-2575 575)(-2225 575);
WIRE 16 -1 (-2575 575)(-2575 525);
WIRE 16 -1 (-2575 525)(-2225 525);
WIRE 16 -1 (-5625 3225)(-5350 3225);
WIRE 16 -1 (-5625 3075)(-5625 3225);
WIRE 16 -1 (-5900 3225)(-5625 3225);
WIRE 16 -1 (-5350 3075)(-5350 3225);
WIRE 16 -1 (-5900 3075)(-5900 3225);
WIRE 16 -1 (-5900 3225)(-5900 3300);
WIRE 16 -1 (-2700 4325)(-3575 4325);
FORCEPROP 0 LAST CDS_PHYS_NET_NAME SMB_INA230_3V3AUX_SCL_R
J 0
(-3535 4373);
PAINT MONO (-3535 4373);
DISPLAY INVISIBLE (-3535 4373);
FORCEPROP 2 LAST SIG_NAME SMB_INA230_3V3AUX_SCL_R
J 0
(-3410 4335);
DISPLAY 0.510638 (-3410 4335);
PAINT WHITE (-3410 4335);
FORCEPROP 2 LASTPROP $XRERR UNIQUE?
J 0
(-3650 4335);
DISPLAY 0.638298 (-3650 4335);
PAINT MONO (-3650 4335);
DISPLAY INVISIBLE (-3650 4335);
DOT 1 (-6600 4675);
DOT 1 (-4800 5500);
DOT 1 (-2575 575);
DOT 1 (-2575 900);
DOT 1 (-2575 1225);
DOT 1 (-2575 1175);
DOT 1 (-2575 1875);
DOT 1 (-2575 2125);
DOT 1 (-2575 2175);
DOT 1 (-2575 2450);
DOT 1 (-2575 2400);
DOT 1 (-2575 2775);
DOT 1 (-2575 2825);
DOT 1 (-2575 1600);
DOT 1 (-2575 1550);
DOT 1 (-2575 1825);
DOT 1 (-2575 850);
DOT 1 (-5625 3225);
DOT 1 (-5625 2625);
DOT 1 (-5900 3225);
DOT 1 (-5900 2700);
DOT 1 (-5350 2550);
FORCENOTE
PCA9548 ADDR: 0XE0 (8-BIT) / 0X70 (7-BIT)
(-5525 3725) 0;
DISPLAY LEFT (-5525 3725);
DISPLAY 1.595745 (-5525 3725);
PAINT SKYBLUE (-5525 3725);
QUIT
